FILE_TYPE = MACRO_DRAWING;
SET COLOR_WIRE YELLOW;
SET COLOR_PROP ORANGE;
SET COLOR_DOT WHITE;
SET COLOR_ARC YELLOW;
SET COLOR_BODY GREEN;
SET COLOR_NOTE PURPLE;
SET PROP_DISPLAY VALUE;
SET PAGE_NUMBER P180;
FORCEADD UNIVERSAL_GND..1
(275 1600);
FORCEPROP 3 LASTPIN (275 1650) SIG_NAME GND\g
J 0
(285 1660);
DISPLAY 0.659574 (285 1660);
PAINT MONO (285 1660);
DISPLAY INVISIBLE (285 1660);
FORCEPROP 2 LAST CDS_LIB pure_quanta_power
J 0
(275 1600);
DISPLAY INVISIBLE (275 1600);
FORCEPROP 1 LAST HDL_POWER GND
J 1
(300 1525);
DISPLAY 0.872340 (300 1525);
PAINT GREEN (300 1525);
DISPLAY INVISIBLE (300 1525);
FORCEPROP 1 LAST PATH I1
J 0
(350 1600);
DISPLAY 0.872340 (350 1600);
PAINT AQUA (350 1600);
DISPLAY INVISIBLE (350 1600);
FORCEADD Q_CAP..1
(1175 2575);
FORCEPROP 1 LAST LOCATION PC142
J 0
(1225 2675);
DISPLAY 0.489362 (1225 2675);
PAINT SKYBLUE (1225 2675);
FORCEPROP 0 LAST $SEC 1
J 0
(1225 2725);
DISPLAY 0.680851 (1225 2725);
PAINT MONO (1225 2725);
DISPLAY INVISIBLE (1225 2725);
FORCEPROP 0 LAST CDS_SEC 1
J 0
(1225 2725);
DISPLAY 1.021277 (1225 2725);
DISPLAY INVISIBLE (1225 2725);
FORCEPROP 1 LASTPIN (1175 2675) $PN 1
J 0
(1185 2655);
DISPLAY 0.489362 (1185 2655);
PAINT MONO (1185 2655);
FORCEPROP 1 LASTPIN (1175 2475) $PN 2
J 0
(1185 2455);
DISPLAY 0.489362 (1185 2455);
PAINT MONO (1185 2455);
FORCEPROP 1 LAST PACK_TYPE C0402
J 0
(1225 2375);
DISPLAY 0.489362 (1225 2375);
PAINT SKYBLUE (1225 2375);
FORCEPROP 1 LAST VOLTAGE 10V
J 0
(1225 2575);
DISPLAY 0.489362 (1225 2575);
PAINT SKYBLUE (1225 2575);
FORCEPROP 1 LAST VALUE 2.2UF
J 0
(1225 2625);
DISPLAY 0.489362 (1225 2625);
PAINT SKYBLUE (1225 2625);
FORCEPROP 1 LAST TOLERANCE 10%
J 0
(1225 2525);
DISPLAY 0.489362 (1225 2525);
PAINT SKYBLUE (1225 2525);
FORCEPROP 1 LAST MATERIAL X6S
J 0
(1225 2475);
DISPLAY 0.489362 (1225 2475);
PAINT SKYBLUE (1225 2475);
FORCEPROP 2 LAST CDS_LIB pure_quanta
J 0
(1175 2575);
DISPLAY INVISIBLE (1175 2575);
FORCEPROP 1 LAST PATH I10
J 0
(1225 2725);
DISPLAY 0.978723 (1225 2725);
PAINT WHITE (1225 2725);
DISPLAY INVISIBLE (1225 2725);
FORCEPROP 1 LAST PART_NUMBER CH5222KEB01
J 0
(1225 2425);
DISPLAY 0.489362 (1225 2425);
PAINT SKYBLUE (1225 2425);
DISPLAY INVISIBLE (1225 2425);
FORCEADD UNIVERSAL_GND..1
(1525 2875);
FORCEPROP 3 LASTPIN (1525 2925) SIG_NAME GND\g
J 0
(1535 2935);
DISPLAY 0.659574 (1535 2935);
PAINT MONO (1535 2935);
DISPLAY INVISIBLE (1535 2935);
FORCEPROP 2 LAST CDS_LIB pure_quanta_power
J 0
(1525 2875);
DISPLAY INVISIBLE (1525 2875);
FORCEPROP 1 LAST HDL_POWER GND
J 1
(1550 2800);
DISPLAY 0.872340 (1550 2800);
PAINT GREEN (1550 2800);
DISPLAY INVISIBLE (1550 2800);
FORCEPROP 1 LAST PATH I11
J 0
(1600 2875);
DISPLAY 0.872340 (1600 2875);
PAINT AQUA (1600 2875);
DISPLAY INVISIBLE (1600 2875);
FORCEADD Q_RES..2
(1175 3125);
FORCEPROP 1 LAST LOCATION PR99
J 0
(1220 3250);
DISPLAY 0.489362 (1220 3250);
PAINT SKYBLUE (1220 3250);
FORCEPROP 0 LAST $SEC 1
J 0
(1225 3300);
DISPLAY 0.680851 (1225 3300);
PAINT MONO (1225 3300);
DISPLAY INVISIBLE (1225 3300);
FORCEPROP 0 LAST CDS_SEC 1
J 0
(1225 3300);
DISPLAY 1.021277 (1225 3300);
DISPLAY INVISIBLE (1225 3300);
FORCEPROP 1 LASTPIN (1175 3225) $PN 1
J 0
(1180 3187);
DISPLAY 0.489362 (1180 3187);
PAINT MONO (1180 3187);
FORCEPROP 1 LASTPIN (1175 3025) $PN 2
J 0
(1180 3035);
DISPLAY 0.489362 (1180 3035);
PAINT MONO (1180 3035);
FORCEPROP 1 LAST WATTAGE 1/16W
J 0
(1225 3100);
DISPLAY 0.489362 (1225 3100);
PAINT SKYBLUE (1225 3100);
FORCEPROP 1 LAST MATERIAL CHIP
J 0
(1225 3050);
DISPLAY 0.489362 (1225 3050);
PAINT SKYBLUE (1225 3050);
FORCEPROP 1 LAST TOLERANCE 1%
J 0
(1225 3150);
DISPLAY 0.489362 (1225 3150);
PAINT SKYBLUE (1225 3150);
FORCEPROP 1 LAST PACK_TYPE 0402LF
J 0
(1225 2950);
DISPLAY 0.489362 (1225 2950);
PAINT SKYBLUE (1225 2950);
FORCEPROP 1 LAST VALUE 2.2
J 0
(1225 3200);
DISPLAY 0.489362 (1225 3200);
PAINT SKYBLUE (1225 3200);
FORCEPROP 2 LAST CDS_LIB pure_quanta
J 0
(1175 3125);
DISPLAY INVISIBLE (1175 3125);
FORCEPROP 1 LAST PATH I12
J 0
(1225 3300);
DISPLAY 0.978723 (1225 3300);
PAINT WHITE (1225 3300);
DISPLAY INVISIBLE (1225 3300);
FORCEPROP 1 LAST PART_NUMBER CS-2202FB01
J 0
(1225 3000);
DISPLAY 0.489362 (1225 3000);
PAINT SKYBLUE (1225 3000);
DISPLAY INVISIBLE (1225 3000);
FORCEADD Q_CAP..1
(1525 3150);
FORCEPROP 1 LAST LOCATION PC144_IOP0_2
J 0
(1575 3250);
DISPLAY 0.489362 (1575 3250);
PAINT SKYBLUE (1575 3250);
FORCEPROP 0 LAST $SEC 1
J 0
(1575 3300);
DISPLAY 0.680851 (1575 3300);
PAINT MONO (1575 3300);
DISPLAY INVISIBLE (1575 3300);
FORCEPROP 0 LAST CDS_SEC 1
J 0
(1575 3300);
DISPLAY 1.021277 (1575 3300);
DISPLAY INVISIBLE (1575 3300);
FORCEPROP 1 LASTPIN (1525 3250) $PN 1
J 0
(1535 3230);
DISPLAY 0.489362 (1535 3230);
PAINT MONO (1535 3230);
FORCEPROP 1 LASTPIN (1525 3050) $PN 2
J 0
(1535 3030);
DISPLAY 0.489362 (1535 3030);
PAINT MONO (1535 3030);
FORCEPROP 1 LAST VALUE 2.2UF
J 0
(1575 3200);
DISPLAY 0.489362 (1575 3200);
PAINT SKYBLUE (1575 3200);
FORCEPROP 1 LAST PACK_TYPE C0402
J 0
(1575 2950);
DISPLAY 0.489362 (1575 2950);
PAINT SKYBLUE (1575 2950);
FORCEPROP 1 LAST TOLERANCE 10%
J 0
(1575 3100);
DISPLAY 0.489362 (1575 3100);
PAINT SKYBLUE (1575 3100);
FORCEPROP 1 LAST MATERIAL X6S
J 0
(1575 3050);
DISPLAY 0.489362 (1575 3050);
PAINT SKYBLUE (1575 3050);
FORCEPROP 1 LAST VOLTAGE 10V
J 0
(1575 3150);
DISPLAY 0.489362 (1575 3150);
PAINT SKYBLUE (1575 3150);
FORCEPROP 2 LAST CDS_LIB pure_quanta
J 0
(1525 3150);
DISPLAY INVISIBLE (1525 3150);
FORCEPROP 1 LAST PATH I13
J 0
(1575 3300);
DISPLAY 0.978723 (1575 3300);
PAINT WHITE (1575 3300);
DISPLAY INVISIBLE (1575 3300);
FORCEPROP 1 LAST PART_NUMBER CH5222KEB01
J 0
(1575 3000);
DISPLAY 0.489362 (1575 3000);
PAINT SKYBLUE (1575 3000);
DISPLAY INVISIBLE (1575 3000);
FORCEADD VCC_CORE..1
(1175 3550);
FORCEPROP 3 LASTPIN (1175 3500) SIG_NAME PVDDCR_CPU1_P0_PVCC\g
J 0
(1185 3510);
DISPLAY 0.659574 (1185 3510);
PAINT MONO (1185 3510);
DISPLAY INVISIBLE (1185 3510);
FORCEPROP 1 LAST HDL_POWER PVDDCR_CPU1_P0_PVCC
J 1
(1175 3600);
DISPLAY 0.489362 (1175 3600);
PAINT GREEN (1175 3600);
FORCEPROP 2 LAST CDS_LIB pure_quanta_power
J 0
(1175 3550);
DISPLAY INVISIBLE (1175 3550);
FORCEPROP 1 LAST PATH I14
J 0
(1225 3575);
DISPLAY 0.872340 (1225 3575);
PAINT AQUA (1225 3575);
DISPLAY INVISIBLE (1225 3575);
FORCEADD ISL99390FRZTR5935..1
(2850 2175);
FORCEPROP 1 LAST LOCATION PU18
J 0
(2550 3050);
DISPLAY 0.489362 (2550 3050);
PAINT SKYBLUE (2550 3050);
FORCEPROP 0 LAST $SEC 1
J 0
(2550 3225);
DISPLAY 0.680851 (2550 3225);
PAINT MONO (2550 3225);
DISPLAY INVISIBLE (2550 3225);
FORCEPROP 2 LAST CDS_SEC 1
J 0
(2600 3175);
DISPLAY 1.021277 (2600 3175);
DISPLAY INVISIBLE (2600 3175);
FORCEPROP 0 LASTPIN (3250 1725) $PN 2
J 0
(3260 1735);
DISPLAY 0.489362 (3260 1735);
PAINT MONO (3260 1735);
FORCEPROP 0 LASTPIN (3250 2525) $PN 33
J 0
(3260 2535);
DISPLAY 0.489362 (3260 2535);
PAINT MONO (3260 2535);
FORCEPROP 0 LASTPIN (2400 1925) $PN 31
J 2
(2390 1935);
DISPLAY 0.489362 (2390 1935);
PAINT MONO (2390 1935);
FORCEPROP 0 LASTPIN (2400 2325) $PN 35
J 2
(2390 2335);
DISPLAY 0.489362 (2390 2335);
PAINT MONO (2390 2335);
FORCEPROP 0 LASTPIN (3250 1875) $PN 6
J 0
(3260 1885);
DISPLAY 0.489362 (3260 1885);
PAINT MONO (3260 1885);
FORCEPROP 0 LASTPIN (3250 1825) $PN 41
J 0
(3260 1835);
DISPLAY 0.489362 (3260 1835);
PAINT MONO (3260 1835);
FORCEPROP 0 LASTPIN (2400 2175) $PN 38
J 2
(2390 2185);
DISPLAY 0.489362 (2390 2185);
PAINT MONO (2390 2185);
FORCEPROP 0 LASTPIN (2400 1875) $PN 37
J 2
(2390 1885);
DISPLAY 0.489362 (2390 1885);
PAINT MONO (2390 1885);
FORCEPROP 0 LASTPIN (3250 1675) $PN 5
J 0
(3260 1685);
DISPLAY 0.489362 (3260 1685);
PAINT MONO (3260 1685);
FORCEPROP 0 LASTPIN (3250 1625) $PN 7_9-20_24
J 0
(3260 1635);
DISPLAY 0.489362 (3260 1635);
PAINT MONO (3260 1635);
FORCEPROP 0 LASTPIN (3250 1575) $PN 40
J 0
(3260 1585);
DISPLAY 0.489362 (3260 1585);
PAINT MONO (3260 1585);
FORCEPROP 0 LASTPIN (3250 2275) $PN 32
J 0
(3260 2285);
DISPLAY 0.489362 (3260 2285);
PAINT MONO (3260 2285);
FORCEPROP 0 LASTPIN (2400 2825) $PN 4
J 2
(2390 2835);
DISPLAY 0.489362 (2390 2835);
PAINT MONO (2390 2835);
FORCEPROP 0 LASTPIN (2400 1575) $PN 34
J 2
(2390 1585);
DISPLAY 0.489362 (2390 1585);
PAINT MONO (2390 1585);
FORCEPROP 0 LASTPIN (2400 2075) $PN 39
J 2
(2390 2085);
DISPLAY 0.489362 (2390 2085);
PAINT MONO (2390 2085);
FORCEPROP 0 LASTPIN (3250 2175) $PN 10_19
J 0
(3260 2185);
DISPLAY 0.489362 (3260 2185);
PAINT MONO (3260 2185);
FORCEPROP 0 LASTPIN (2400 1675) $PN 36
J 2
(2390 1685);
DISPLAY 0.489362 (2390 1685);
PAINT MONO (2390 1685);
FORCEPROP 0 LASTPIN (2400 2525) $PN 3
J 2
(2390 2535);
DISPLAY 0.489362 (2390 2535);
PAINT MONO (2390 2535);
FORCEPROP 0 LASTPIN (3250 2825) $PN 25_29
J 0
(3260 2835);
DISPLAY 0.489362 (3260 2835);
PAINT MONO (3260 2835);
FORCEPROP 0 LASTPIN (3250 2775) $PN 30
J 0
(3260 2785);
DISPLAY 0.489362 (3260 2785);
PAINT MONO (3260 2785);
FORCEPROP 0 LASTPIN (3250 1925) $PN 1
J 0
(3260 1935);
DISPLAY 0.489362 (3260 1935);
PAINT MONO (3260 1935);
FORCEPROP 2 LAST VALUE ISL99390FRZ-TR5935
J 0
(2550 3125);
DISPLAY 0.489362 (2550 3125);
PAINT SKYBLUE (2550 3125);
FORCEPROP 2 LAST PART_TYPE SMLF
J 0
(2550 3175);
DISPLAY 0.638298 (2550 3175);
FORCEPROP 1 LAST MATERIAL IC
J 0
(2550 2900);
DISPLAY 0.489362 (2550 2900);
PAINT SKYBLUE (2550 2900);
FORCEPROP 1 LAST CDS_LMAN_SYM_OUTLINE -300,700,250,-650
J 0
(2850 2175);
DISPLAY 0.468085 (2850 2175);
PAINT GREEN (2850 2175);
DISPLAY INVISIBLE (2850 2175);
FORCEPROP 1 LAST NEEDS_NO_SIZE TRUE
J 0
(2850 2175);
DISPLAY 0.723404 (2850 2175);
PAINT GREEN (2850 2175);
DISPLAY INVISIBLE (2850 2175);
FORCEPROP 2 LAST CDS_LIB pure_quanta
J 0
(2850 2175);
DISPLAY INVISIBLE (2850 2175);
FORCEPROP 1 LAST PATH I15
J 0
(2850 2175);
DISPLAY 0.723404 (2850 2175);
PAINT GREEN (2850 2175);
DISPLAY INVISIBLE (2850 2175);
FORCEPROP 1 LAST PART_NUMBER AL099390004
J 0
(2550 2975);
DISPLAY 0.489362 (2550 2975);
PAINT SKYBLUE (2550 2975);
DISPLAY INVISIBLE (2550 2975);
FORCEADD UNIVERSAL_GND..1
(3500 1450);
FORCEPROP 3 LASTPIN (3500 1500) SIG_NAME GND\g
J 0
(3510 1510);
DISPLAY 0.659574 (3510 1510);
PAINT MONO (3510 1510);
DISPLAY INVISIBLE (3510 1510);
FORCEPROP 2 LAST CDS_LIB pure_quanta_power
J 0
(3500 1450);
PAINT MONO (3500 1450);
DISPLAY INVISIBLE (3500 1450);
FORCEPROP 1 LAST HDL_POWER GND
J 1
(3525 1375);
DISPLAY 0.872340 (3525 1375);
PAINT GREEN (3525 1375);
DISPLAY INVISIBLE (3525 1375);
FORCEPROP 1 LAST PATH I16
J 0
(3575 1450);
DISPLAY 0.872340 (3575 1450);
PAINT AQUA (3575 1450);
DISPLAY INVISIBLE (3575 1450);
FORCEADD Q_RES..1
(4125 2525);
FORCEPROP 1 LAST LOCATION PR102
J 0
(3875 2575);
DISPLAY 0.489362 (3875 2575);
PAINT SKYBLUE (3875 2575);
FORCEPROP 0 LAST $SEC 1
J 0
(4300 2600);
DISPLAY 0.680851 (4300 2600);
PAINT MONO (4300 2600);
DISPLAY INVISIBLE (4300 2600);
FORCEPROP 0 LAST CDS_SEC 1
J 0
(4300 2600);
DISPLAY 1.021277 (4300 2600);
DISPLAY INVISIBLE (4300 2600);
FORCEPROP 1 LASTPIN (4025 2525) $PN 1
J 0
(4037 2537);
DISPLAY 0.787234 (4037 2537);
PAINT MONO (4037 2537);
DISPLAY INVISIBLE (4037 2537);
FORCEPROP 1 LASTPIN (4225 2525) $PN 2
J 0
(4187 2537);
DISPLAY 0.787234 (4187 2537);
PAINT MONO (4187 2537);
DISPLAY INVISIBLE (4187 2537);
FORCEPROP 1 LAST VALUE 5.6
J 2
(4075 2575);
DISPLAY 0.489362 (4075 2575);
PAINT SKYBLUE (4075 2575);
FORCEPROP 1 LAST PACK_TYPE 0402LF
J 0
(4525 2450);
DISPLAY 0.489362 (4525 2450);
PAINT SKYBLUE (4525 2450);
FORCEPROP 1 LAST WATTAGE 1/16W
J 2
(4300 2575);
DISPLAY 0.489362 (4300 2575);
PAINT SKYBLUE (4300 2575);
FORCEPROP 1 LAST MATERIAL CHIP
J 0
(3975 2450);
DISPLAY 0.489362 (3975 2450);
PAINT SKYBLUE (3975 2450);
FORCEPROP 1 LAST TOLERANCE 1%
J 0
(4100 2575);
DISPLAY 0.489362 (4100 2575);
PAINT SKYBLUE (4100 2575);
FORCEPROP 2 LAST CDS_LIB pure_quanta
J 0
(4125 2525);
DISPLAY INVISIBLE (4125 2525);
FORCEPROP 1 LAST PATH I17
J 0
(4075 2675);
DISPLAY 0.978723 (4075 2675);
PAINT WHITE (4075 2675);
DISPLAY INVISIBLE (4075 2675);
FORCEPROP 1 LAST PART_NUMBER CS-5602FB01
J 0
(4150 2450);
DISPLAY 0.489362 (4150 2450);
PAINT SKYBLUE (4150 2450);
DISPLAY INVISIBLE (4150 2450);
FORCEADD Q_CAP..1
(3675 3100);
FORCEPROP 1 LAST LOCATION PC149_2
J 0
(3725 3250);
DISPLAY 0.489362 (3725 3250);
PAINT SKYBLUE (3725 3250);
FORCEPROP 0 LAST $SEC 1
J 0
(3725 3250);
DISPLAY 0.680851 (3725 3250);
PAINT MONO (3725 3250);
DISPLAY INVISIBLE (3725 3250);
FORCEPROP 0 LAST CDS_SEC 1
J 0
(3725 3250);
DISPLAY 1.021277 (3725 3250);
DISPLAY INVISIBLE (3725 3250);
FORCEPROP 1 LASTPIN (3675 3200) $PN 1
J 0
(3685 3180);
DISPLAY 0.489362 (3685 3180);
PAINT MONO (3685 3180);
FORCEPROP 1 LASTPIN (3675 3000) $PN 2
J 0
(3685 2980);
DISPLAY 0.489362 (3685 2980);
PAINT MONO (3685 2980);
FORCEPROP 1 LAST VALUE 0.1UF
J 0
(3725 3200);
DISPLAY 0.489362 (3725 3200);
PAINT SKYBLUE (3725 3200);
FORCEPROP 1 LAST PACK_TYPE 0402
J 0
(3725 2950);
DISPLAY 0.489362 (3725 2950);
PAINT SKYBLUE (3725 2950);
FORCEPROP 1 LAST VOLTAGE 25V
J 0
(3725 3150);
DISPLAY 0.489362 (3725 3150);
PAINT SKYBLUE (3725 3150);
FORCEPROP 1 LAST MATERIAL X7R
J 0
(3725 3050);
DISPLAY 0.489362 (3725 3050);
PAINT SKYBLUE (3725 3050);
FORCEPROP 1 LAST TOLERANCE 10%
J 0
(3725 3100);
DISPLAY 0.489362 (3725 3100);
PAINT SKYBLUE (3725 3100);
FORCEPROP 2 LAST CDS_LIB pure_quanta
J 0
(3675 3100);
DISPLAY INVISIBLE (3675 3100);
FORCEPROP 1 LAST PATH I18
J 0
(3725 3250);
DISPLAY 0.978723 (3725 3250);
PAINT WHITE (3725 3250);
DISPLAY INVISIBLE (3725 3250);
FORCEPROP 1 LAST PART_NUMBER CH4104K1B00
J 0
(3725 3000);
DISPLAY 0.489362 (3725 3000);
PAINT SKYBLUE (3725 3000);
DISPLAY INVISIBLE (3725 3000);
FORCEADD UNIVERSAL_GND..1
(250 4350);
FORCEPROP 3 LASTPIN (250 4400) SIG_NAME GND\g
J 0
(260 4410);
DISPLAY 0.659574 (260 4410);
PAINT MONO (260 4410);
DISPLAY INVISIBLE (260 4410);
FORCEPROP 2 LAST CDS_LIB pure_quanta_power
J 0
(250 4350);
DISPLAY INVISIBLE (250 4350);
FORCEPROP 1 LAST HDL_POWER GND
J 1
(275 4275);
DISPLAY 0.872340 (275 4275);
PAINT GREEN (275 4275);
DISPLAY INVISIBLE (275 4275);
FORCEPROP 1 LAST PATH I19
J 0
(325 4350);
DISPLAY 0.872340 (325 4350);
PAINT AQUA (325 4350);
DISPLAY INVISIBLE (325 4350);
FORCEADD Q_CAP..1
(275 1800);
FORCEPROP 1 LAST LOCATION PC146_8
J 0
(325 1900);
DISPLAY 0.489362 (325 1900);
PAINT SKYBLUE (325 1900);
FORCEPROP 0 LAST $SEC 1
J 0
(325 1925);
DISPLAY 0.680851 (325 1925);
PAINT MONO (325 1925);
DISPLAY INVISIBLE (325 1925);
FORCEPROP 0 LAST CDS_SEC 1
J 0
(525 1850);
DISPLAY 1.021277 (525 1850);
DISPLAY INVISIBLE (525 1850);
FORCEPROP 1 LASTPIN (275 1900) $PN 1
J 0
(285 1880);
DISPLAY 0.489362 (285 1880);
PAINT MONO (285 1880);
FORCEPROP 1 LASTPIN (275 1700) $PN 2
J 0
(285 1680);
DISPLAY 0.489362 (285 1680);
PAINT MONO (285 1680);
FORCEPROP 1 LAST TOLERANCE 10%
J 0
(325 1750);
DISPLAY 0.489362 (325 1750);
PAINT SKYBLUE (325 1750);
FORCEPROP 1 LAST MATERIAL X7R
J 0
(325 1700);
DISPLAY 0.489362 (325 1700);
PAINT SKYBLUE (325 1700);
FORCEPROP 1 LAST PACK_TYPE 0402
J 0
(325 1600);
DISPLAY 0.489362 (325 1600);
PAINT SKYBLUE (325 1600);
FORCEPROP 1 LAST VALUE 0.1UF
J 0
(325 1850);
DISPLAY 0.489362 (325 1850);
PAINT SKYBLUE (325 1850);
FORCEPROP 1 LAST VOLTAGE 25V
J 0
(325 1800);
DISPLAY 0.489362 (325 1800);
PAINT SKYBLUE (325 1800);
FORCEPROP 2 LAST CDS_LIB pure_quanta
J 0
(275 1800);
DISPLAY INVISIBLE (275 1800);
FORCEPROP 1 LAST PATH I2
J 0
(325 1950);
DISPLAY 0.978723 (325 1950);
PAINT WHITE (325 1950);
DISPLAY INVISIBLE (325 1950);
FORCEPROP 1 LAST PART_NUMBER CH4104K1B00
J 0
(325 1650);
DISPLAY 0.489362 (325 1650);
PAINT SKYBLUE (325 1650);
DISPLAY INVISIBLE (325 1650);
FORCEADD Q_CAP..1
(250 4600);
FORCEPROP 1 LAST LOCATION PC145_7
J 0
(300 4700);
DISPLAY 0.489362 (300 4700);
PAINT SKYBLUE (300 4700);
FORCEPROP 0 LAST $SEC 1
J 0
(300 4725);
DISPLAY 0.680851 (300 4725);
PAINT MONO (300 4725);
DISPLAY INVISIBLE (300 4725);
FORCEPROP 0 LAST CDS_SEC 1
J 0
(500 4650);
DISPLAY 1.021277 (500 4650);
DISPLAY INVISIBLE (500 4650);
FORCEPROP 1 LASTPIN (250 4700) $PN 1
J 0
(260 4680);
DISPLAY 0.489362 (260 4680);
PAINT MONO (260 4680);
FORCEPROP 1 LASTPIN (250 4500) $PN 2
J 0
(260 4480);
DISPLAY 0.489362 (260 4480);
PAINT MONO (260 4480);
FORCEPROP 1 LAST MATERIAL X7R
J 0
(300 4500);
DISPLAY 0.489362 (300 4500);
PAINT SKYBLUE (300 4500);
FORCEPROP 1 LAST PACK_TYPE 0402
J 0
(300 4400);
DISPLAY 0.489362 (300 4400);
PAINT SKYBLUE (300 4400);
FORCEPROP 1 LAST VOLTAGE 25V
J 0
(300 4600);
DISPLAY 0.489362 (300 4600);
PAINT SKYBLUE (300 4600);
FORCEPROP 1 LAST VALUE 0.1UF
J 0
(300 4650);
DISPLAY 0.489362 (300 4650);
PAINT SKYBLUE (300 4650);
FORCEPROP 1 LAST TOLERANCE 10%
J 0
(300 4550);
DISPLAY 0.489362 (300 4550);
PAINT SKYBLUE (300 4550);
FORCEPROP 2 LAST CDS_LIB pure_quanta
J 0
(250 4600);
DISPLAY INVISIBLE (250 4600);
FORCEPROP 1 LAST PATH I20
J 0
(300 4750);
DISPLAY 0.978723 (300 4750);
PAINT WHITE (300 4750);
DISPLAY INVISIBLE (300 4750);
FORCEPROP 1 LAST PART_NUMBER CH4104K1B00
J 0
(300 4450);
DISPLAY 0.489362 (300 4450);
PAINT SKYBLUE (300 4450);
DISPLAY INVISIBLE (300 4450);
FORCEADD UNIVERSAL_GND..1
(875 4300);
FORCEPROP 3 LASTPIN (875 4350) SIG_NAME GND\g
J 0
(885 4360);
DISPLAY 0.659574 (885 4360);
PAINT MONO (885 4360);
DISPLAY INVISIBLE (885 4360);
FORCEPROP 2 LAST CDS_LIB pure_quanta_power
J 0
(875 4300);
PAINT MONO (875 4300);
DISPLAY INVISIBLE (875 4300);
FORCEPROP 1 LAST HDL_POWER GND
J 1
(900 4225);
DISPLAY 0.872340 (900 4225);
PAINT GREEN (900 4225);
DISPLAY INVISIBLE (900 4225);
FORCEPROP 1 LAST PATH I21
J 0
(950 4300);
DISPLAY 0.872340 (950 4300);
PAINT AQUA (950 4300);
DISPLAY INVISIBLE (950 4300);
FORCEADD Q_RES..2
R 2
(875 4525);
FORCEPROP 1 LAST LOCATION PR98
J 2
(830 4650);
DISPLAY 0.489362 (830 4650);
PAINT SKYBLUE (830 4650);
FORCEPROP 0 LAST $SEC 1
J 2
(825 4700);
DISPLAY 0.680851 (825 4700);
PAINT MONO (825 4700);
DISPLAY INVISIBLE (825 4700);
FORCEPROP 0 LAST CDS_SEC 1
J 2
(825 4700);
DISPLAY 1.021277 (825 4700);
DISPLAY INVISIBLE (825 4700);
FORCEPROP 1 LASTPIN (875 4625) $PN 1
J 2
(870 4587);
DISPLAY 0.489362 (870 4587);
PAINT MONO (870 4587);
FORCEPROP 1 LASTPIN (875 4425) $PN 2
J 2
(870 4435);
DISPLAY 0.489362 (870 4435);
PAINT MONO (870 4435);
FORCEPROP 1 LAST MATERIAL EMPTY
J 2
(825 4450);
DISPLAY 0.489362 (825 4450);
PAINT RED (825 4450);
FORCEPROP 1 LAST VALUE 8.87K
J 2
(820 4600);
DISPLAY 0.489362 (820 4600);
PAINT SKYBLUE (820 4600);
FORCEPROP 1 LAST PACK_TYPE 0402LF
J 2
(825 4350);
DISPLAY 0.489362 (825 4350);
PAINT SKYBLUE (825 4350);
FORCEPROP 1 LAST WATTAGE 1/16W
J 2
(825 4500);
DISPLAY 0.489362 (825 4500);
PAINT SKYBLUE (825 4500);
FORCEPROP 1 LAST TOLERANCE 1%
J 2
(820 4550);
DISPLAY 0.489362 (820 4550);
PAINT SKYBLUE (820 4550);
FORCEPROP 2 LAST CDS_LIB pure_quanta
J 2
(875 4525);
DISPLAY INVISIBLE (875 4525);
FORCEPROP 1 LAST PATH I22
J 2
(825 4700);
DISPLAY 0.978723 (825 4700);
PAINT WHITE (825 4700);
DISPLAY INVISIBLE (825 4700);
FORCEPROP 1 LAST PART_NUMBER CS28872FB01
J 2
(825 4400);
DISPLAY 0.489362 (825 4400);
PAINT SKYBLUE (825 4400);
DISPLAY INVISIBLE (825 4400);
FORCEADD OFFPAGE..1
(1325 4375);
FORCEPROP 2 LAST $XR0 200 
J 0
(1043 4375);
DISPLAY 0.638298 (1043 4375);
PAINT MONO (1043 4375);
FORCEPROP 2 LAST CDS_LIB standard
J 0
(1325 4375);
DISPLAY INVISIBLE (1325 4375);
FORCEPROP 1 LAST OFFPAGE TRUE
J 0
(1650 4250);
DISPLAY 0.872340 (1650 4250);
PAINT GREEN (1650 4250);
DISPLAY INVISIBLE (1650 4250);
FORCEPROP 1 LAST COMMENT_BODY TRUE
J 0
(1450 4275);
DISPLAY 0.872340 (1450 4275);
PAINT GREEN (1450 4275);
DISPLAY INVISIBLE (1450 4275);
FORCEPROP 2 LAST PATH I23
J 0
(1050 4425);
DISPLAY 0.680851 (1050 4425);
DISPLAY INVISIBLE (1050 4425);
FORCEADD OFFPAGE..5
(1325 4475);
FORCEPROP 2 LAST $XR2 200 
J 0
(1070 4511);
DISPLAY 0.638298 (1070 4511);
PAINT MONO (1070 4511);
FORCEPROP 2 LAST $XR1 206 
J 0
(1070 4439);
DISPLAY 0.638298 (1070 4439);
PAINT MONO (1070 4439);
FORCEPROP 2 LAST $XR0 205 
J 0
(1070 4475);
DISPLAY 0.638298 (1070 4475);
PAINT MONO (1070 4475);
FORCEPROP 2 LAST CDS_LIB standard
J 0
(1325 4475);
DISPLAY INVISIBLE (1325 4475);
FORCEPROP 1 LAST OFFPAGE TRUE
J 0
(1650 4350);
DISPLAY 0.872340 (1650 4350);
PAINT GREEN (1650 4350);
DISPLAY INVISIBLE (1650 4350);
FORCEPROP 1 LAST COMMENT_BODY TRUE
J 0
(1425 4400);
DISPLAY 0.872340 (1425 4400);
PAINT GREEN (1425 4400);
DISPLAY INVISIBLE (1425 4400);
FORCEPROP 2 LAST PATH I24
J 0
(1075 4550);
DISPLAY 0.680851 (1075 4550);
DISPLAY INVISIBLE (1075 4550);
FORCEADD OFFPAGE..1
(1325 4875);
FORCEPROP 2 LAST $XR5 206 
J 0
(443 4875);
DISPLAY 0.638298 (443 4875);
PAINT MONO (443 4875);
FORCEPROP 2 LAST $XR4 205 
J 0
(563 4875);
DISPLAY 0.638298 (563 4875);
PAINT MONO (563 4875);
FORCEPROP 2 LAST $XR3 203 
J 0
(683 4875);
DISPLAY 0.638298 (683 4875);
PAINT MONO (683 4875);
FORCEPROP 2 LAST $XR2 202 
J 0
(803 4875);
DISPLAY 0.638298 (803 4875);
PAINT MONO (803 4875);
FORCEPROP 2 LAST $XR1 201 
J 0
(923 4875);
DISPLAY 0.638298 (923 4875);
PAINT MONO (923 4875);
FORCEPROP 2 LAST $XR0 200 
J 0
(1043 4875);
DISPLAY 0.638298 (1043 4875);
PAINT MONO (1043 4875);
FORCEPROP 2 LAST CDS_LIB standard
J 0
(1325 4875);
DISPLAY INVISIBLE (1325 4875);
FORCEPROP 1 LAST OFFPAGE TRUE
J 0
(1650 4750);
DISPLAY 0.872340 (1650 4750);
PAINT GREEN (1650 4750);
DISPLAY INVISIBLE (1650 4750);
FORCEPROP 1 LAST COMMENT_BODY TRUE
J 0
(1450 4775);
DISPLAY 0.872340 (1450 4775);
PAINT GREEN (1450 4775);
DISPLAY INVISIBLE (1450 4775);
FORCEPROP 2 LAST PATH I25
J 0
(1050 4925);
DISPLAY 0.680851 (1050 4925);
DISPLAY INVISIBLE (1050 4925);
FORCEADD OFFPAGE..5
(1325 4975);
FORCEPROP 2 LAST $XR0 200 
J 0
(1070 4975);
DISPLAY 0.638298 (1070 4975);
PAINT MONO (1070 4975);
FORCEPROP 2 LAST CDS_LIB standard
J 0
(1325 4975);
DISPLAY INVISIBLE (1325 4975);
FORCEPROP 1 LAST OFFPAGE TRUE
J 0
(1650 4850);
DISPLAY 0.872340 (1650 4850);
PAINT GREEN (1650 4850);
DISPLAY INVISIBLE (1650 4850);
FORCEPROP 1 LAST COMMENT_BODY TRUE
J 0
(1425 4900);
DISPLAY 0.872340 (1425 4900);
PAINT GREEN (1425 4900);
DISPLAY INVISIBLE (1425 4900);
FORCEPROP 2 LAST PATH I26
J 0
(1075 5025);
DISPLAY 0.680851 (1075 5025);
DISPLAY INVISIBLE (1075 5025);
FORCEADD UNIVERSAL_GND..1
(1275 5050);
FORCEPROP 3 LASTPIN (1275 5100) SIG_NAME GND\g
J 0
(1285 5110);
DISPLAY 0.659574 (1285 5110);
PAINT MONO (1285 5110);
DISPLAY INVISIBLE (1285 5110);
FORCEPROP 2 LAST CDS_LIB pure_quanta_power
J 0
(1275 5050);
DISPLAY INVISIBLE (1275 5050);
FORCEPROP 1 LAST HDL_POWER GND
J 1
(1300 4975);
DISPLAY 0.872340 (1300 4975);
PAINT GREEN (1300 4975);
DISPLAY INVISIBLE (1300 4975);
FORCEPROP 1 LAST PATH I27
J 0
(1350 5050);
DISPLAY 0.872340 (1350 5050);
PAINT AQUA (1350 5050);
DISPLAY INVISIBLE (1350 5050);
FORCEADD Q_CAP..1
(1275 5250);
FORCEPROP 1 LAST LOCATION PC143
J 0
(1325 5350);
DISPLAY 0.489362 (1325 5350);
PAINT SKYBLUE (1325 5350);
FORCEPROP 0 LAST $SEC 1
J 0
(1325 5400);
DISPLAY 0.680851 (1325 5400);
PAINT MONO (1325 5400);
DISPLAY INVISIBLE (1325 5400);
FORCEPROP 0 LAST CDS_SEC 1
J 0
(1325 5400);
DISPLAY 1.021277 (1325 5400);
DISPLAY INVISIBLE (1325 5400);
FORCEPROP 1 LASTPIN (1275 5350) $PN 1
J 0
(1285 5330);
DISPLAY 0.489362 (1285 5330);
PAINT MONO (1285 5330);
FORCEPROP 1 LASTPIN (1275 5150) $PN 2
J 0
(1285 5130);
DISPLAY 0.489362 (1285 5130);
PAINT MONO (1285 5130);
FORCEPROP 1 LAST PACK_TYPE C0402
J 0
(1325 5050);
DISPLAY 0.489362 (1325 5050);
PAINT SKYBLUE (1325 5050);
FORCEPROP 1 LAST VOLTAGE 10V
J 0
(1325 5250);
DISPLAY 0.489362 (1325 5250);
PAINT SKYBLUE (1325 5250);
FORCEPROP 1 LAST VALUE 2.2UF
J 0
(1325 5300);
DISPLAY 0.489362 (1325 5300);
PAINT SKYBLUE (1325 5300);
FORCEPROP 1 LAST TOLERANCE 10%
J 0
(1325 5200);
DISPLAY 0.489362 (1325 5200);
PAINT SKYBLUE (1325 5200);
FORCEPROP 1 LAST MATERIAL X6S
J 0
(1325 5150);
DISPLAY 0.489362 (1325 5150);
PAINT SKYBLUE (1325 5150);
FORCEPROP 2 LAST CDS_LIB pure_quanta
J 0
(1275 5250);
DISPLAY INVISIBLE (1275 5250);
FORCEPROP 1 LAST PATH I28
J 0
(1325 5400);
DISPLAY 0.978723 (1325 5400);
PAINT WHITE (1325 5400);
DISPLAY INVISIBLE (1325 5400);
FORCEPROP 1 LAST PART_NUMBER CH5222KEB01
J 0
(1325 5100);
DISPLAY 0.489362 (1325 5100);
PAINT SKYBLUE (1325 5100);
DISPLAY INVISIBLE (1325 5100);
FORCEADD Q_RES..2
(1275 5800);
FORCEPROP 1 LAST LOCATION PR100
J 0
(1320 5925);
DISPLAY 0.489362 (1320 5925);
PAINT SKYBLUE (1320 5925);
FORCEPROP 0 LAST $SEC 1
J 0
(1325 5975);
DISPLAY 0.680851 (1325 5975);
PAINT MONO (1325 5975);
DISPLAY INVISIBLE (1325 5975);
FORCEPROP 0 LAST CDS_SEC 1
J 0
(1325 5975);
DISPLAY 1.021277 (1325 5975);
DISPLAY INVISIBLE (1325 5975);
FORCEPROP 1 LASTPIN (1275 5900) $PN 1
J 0
(1280 5862);
DISPLAY 0.489362 (1280 5862);
PAINT MONO (1280 5862);
FORCEPROP 1 LASTPIN (1275 5700) $PN 2
J 0
(1280 5710);
DISPLAY 0.489362 (1280 5710);
PAINT MONO (1280 5710);
FORCEPROP 1 LAST WATTAGE 1/16W
J 0
(1325 5775);
DISPLAY 0.489362 (1325 5775);
PAINT SKYBLUE (1325 5775);
FORCEPROP 1 LAST MATERIAL CHIP
J 0
(1325 5725);
DISPLAY 0.489362 (1325 5725);
PAINT SKYBLUE (1325 5725);
FORCEPROP 1 LAST TOLERANCE 1%
J 0
(1325 5825);
DISPLAY 0.489362 (1325 5825);
PAINT SKYBLUE (1325 5825);
FORCEPROP 1 LAST VALUE 2.2
J 0
(1325 5875);
DISPLAY 0.489362 (1325 5875);
PAINT SKYBLUE (1325 5875);
FORCEPROP 1 LAST PACK_TYPE 0402LF
J 0
(1325 5625);
DISPLAY 0.489362 (1325 5625);
PAINT SKYBLUE (1325 5625);
FORCEPROP 2 LAST CDS_LIB pure_quanta
J 0
(1275 5800);
DISPLAY INVISIBLE (1275 5800);
FORCEPROP 1 LAST PATH I29
J 0
(1325 5975);
DISPLAY 0.978723 (1325 5975);
PAINT WHITE (1325 5975);
DISPLAY INVISIBLE (1325 5975);
FORCEPROP 1 LAST PART_NUMBER CS-2202FB01
J 0
(1325 5675);
DISPLAY 0.489362 (1325 5675);
PAINT SKYBLUE (1325 5675);
DISPLAY INVISIBLE (1325 5675);
FORCEADD UNIVERSAL_GND..1
(850 1450);
FORCEPROP 3 LASTPIN (850 1500) SIG_NAME GND\g
J 0
(860 1510);
DISPLAY 0.659574 (860 1510);
PAINT MONO (860 1510);
DISPLAY INVISIBLE (860 1510);
FORCEPROP 2 LAST CDS_LIB pure_quanta_power
J 0
(850 1450);
PAINT MONO (850 1450);
DISPLAY INVISIBLE (850 1450);
FORCEPROP 1 LAST HDL_POWER GND
J 1
(875 1375);
DISPLAY 0.872340 (875 1375);
PAINT GREEN (875 1375);
DISPLAY INVISIBLE (875 1375);
FORCEPROP 1 LAST PATH I3
J 0
(925 1450);
DISPLAY 0.872340 (925 1450);
PAINT AQUA (925 1450);
DISPLAY INVISIBLE (925 1450);
FORCEADD UNIVERSAL_GND..1
(1625 5550);
FORCEPROP 3 LASTPIN (1625 5600) SIG_NAME GND\g
J 0
(1635 5610);
DISPLAY 0.659574 (1635 5610);
PAINT MONO (1635 5610);
DISPLAY INVISIBLE (1635 5610);
FORCEPROP 2 LAST CDS_LIB pure_quanta_power
J 0
(1625 5550);
DISPLAY INVISIBLE (1625 5550);
FORCEPROP 1 LAST HDL_POWER GND
J 1
(1650 5475);
DISPLAY 0.872340 (1650 5475);
PAINT GREEN (1650 5475);
DISPLAY INVISIBLE (1650 5475);
FORCEPROP 1 LAST PATH I30
J 0
(1700 5550);
DISPLAY 0.872340 (1700 5550);
PAINT AQUA (1700 5550);
DISPLAY INVISIBLE (1700 5550);
FORCEADD Q_CAP..1
(1625 5825);
FORCEPROP 1 LAST LOCATION PC147_IOP0_1
J 0
(1675 5925);
DISPLAY 0.489362 (1675 5925);
PAINT SKYBLUE (1675 5925);
FORCEPROP 0 LAST $SEC 1
J 0
(1675 5975);
DISPLAY 0.680851 (1675 5975);
PAINT MONO (1675 5975);
DISPLAY INVISIBLE (1675 5975);
FORCEPROP 0 LAST CDS_SEC 1
J 0
(1675 5975);
DISPLAY 1.021277 (1675 5975);
DISPLAY INVISIBLE (1675 5975);
FORCEPROP 1 LASTPIN (1625 5925) $PN 1
J 0
(1635 5905);
DISPLAY 0.489362 (1635 5905);
PAINT MONO (1635 5905);
FORCEPROP 1 LASTPIN (1625 5725) $PN 2
J 0
(1635 5705);
DISPLAY 0.489362 (1635 5705);
PAINT MONO (1635 5705);
FORCEPROP 1 LAST TOLERANCE 10%
J 0
(1675 5775);
DISPLAY 0.489362 (1675 5775);
PAINT SKYBLUE (1675 5775);
FORCEPROP 1 LAST PACK_TYPE C0402
J 0
(1675 5625);
DISPLAY 0.489362 (1675 5625);
PAINT SKYBLUE (1675 5625);
FORCEPROP 1 LAST VOLTAGE 10V
J 0
(1675 5825);
DISPLAY 0.489362 (1675 5825);
PAINT SKYBLUE (1675 5825);
FORCEPROP 1 LAST VALUE 2.2UF
J 0
(1675 5875);
DISPLAY 0.489362 (1675 5875);
PAINT SKYBLUE (1675 5875);
FORCEPROP 1 LAST MATERIAL X6S
J 0
(1675 5725);
DISPLAY 0.489362 (1675 5725);
PAINT SKYBLUE (1675 5725);
FORCEPROP 2 LAST CDS_LIB pure_quanta
J 0
(1625 5825);
DISPLAY INVISIBLE (1625 5825);
FORCEPROP 1 LAST PATH I31
J 0
(1675 5975);
DISPLAY 0.978723 (1675 5975);
PAINT WHITE (1675 5975);
DISPLAY INVISIBLE (1675 5975);
FORCEPROP 1 LAST PART_NUMBER CH5222KEB01
J 0
(1675 5675);
DISPLAY 0.489362 (1675 5675);
PAINT SKYBLUE (1675 5675);
DISPLAY INVISIBLE (1675 5675);
FORCEADD VCC_CORE..1
(1275 6225);
FORCEPROP 3 LASTPIN (1275 6175) SIG_NAME PVDDCR_CPU1_P0_PVCC\g
J 0
(1285 6185);
DISPLAY 0.659574 (1285 6185);
PAINT MONO (1285 6185);
DISPLAY INVISIBLE (1285 6185);
FORCEPROP 1 LAST HDL_POWER PVDDCR_CPU1_P0_PVCC
J 1
(1275 6275);
DISPLAY 0.489362 (1275 6275);
PAINT GREEN (1275 6275);
FORCEPROP 2 LAST CDS_LIB pure_quanta_power
J 0
(1275 6225);
DISPLAY INVISIBLE (1275 6225);
FORCEPROP 1 LAST PATH I32
J 0
(1325 6250);
DISPLAY 0.872340 (1325 6250);
PAINT AQUA (1325 6250);
DISPLAY INVISIBLE (1325 6250);
FORCEADD UNIVERSAL_GND..1
(3500 4250);
FORCEPROP 3 LASTPIN (3500 4300) SIG_NAME GND\g
J 0
(3510 4310);
DISPLAY 0.659574 (3510 4310);
PAINT MONO (3510 4310);
DISPLAY INVISIBLE (3510 4310);
FORCEPROP 2 LAST CDS_LIB pure_quanta_power
J 0
(3500 4250);
PAINT MONO (3500 4250);
DISPLAY INVISIBLE (3500 4250);
FORCEPROP 1 LAST HDL_POWER GND
J 1
(3525 4175);
DISPLAY 0.872340 (3525 4175);
PAINT GREEN (3525 4175);
DISPLAY INVISIBLE (3525 4175);
FORCEPROP 1 LAST PATH I33
J 0
(3575 4250);
DISPLAY 0.872340 (3575 4250);
PAINT AQUA (3575 4250);
DISPLAY INVISIBLE (3575 4250);
FORCEADD Q_RES..1
(3950 5325);
FORCEPROP 1 LAST LOCATION PR101
J 0
(3925 5375);
DISPLAY 0.489362 (3925 5375);
PAINT SKYBLUE (3925 5375);
FORCEPROP 2 LAST $SEC 1
J 0
(3900 5525);
DISPLAY 0.680851 (3900 5525);
PAINT MONO (3900 5525);
DISPLAY INVISIBLE (3900 5525);
FORCEPROP 2 LAST CDS_SEC 1
J 0
(3900 5525);
DISPLAY 1.021277 (3900 5525);
DISPLAY INVISIBLE (3900 5525);
FORCEPROP 1 LASTPIN (3850 5325) $PN 1
J 0
(3862 5337);
DISPLAY 0.489362 (3862 5337);
FORCEPROP 1 LASTPIN (4050 5325) $PN 2
J 0
(4012 5337);
DISPLAY 0.489362 (4012 5337);
FORCEPROP 1 LAST VALUE 5.6
J 2
(3800 5400);
DISPLAY 0.489362 (3800 5400);
PAINT SKYBLUE (3800 5400);
FORCEPROP 1 LAST PACK_TYPE 0402LF
J 0
(4025 5275);
DISPLAY 0.489362 (4025 5275);
PAINT SKYBLUE (4025 5275);
FORCEPROP 1 LAST TOLERANCE 1%
J 0
(3825 5400);
DISPLAY 0.489362 (3825 5400);
PAINT SKYBLUE (3825 5400);
FORCEPROP 1 LAST MATERIAL CHIP
J 0
(4025 5225);
DISPLAY 0.489362 (4025 5225);
PAINT SKYBLUE (4025 5225);
FORCEPROP 1 LAST WATTAGE 1/16W
J 2
(4150 5400);
DISPLAY 0.489362 (4150 5400);
PAINT SKYBLUE (4150 5400);
FORCEPROP 2 LAST CDS_LIB pure_quanta
J 0
(3950 5325);
PAINT MONO (3950 5325);
DISPLAY INVISIBLE (3950 5325);
FORCEPROP 1 LAST PATH I34
J 0
(3900 5475);
DISPLAY 0.978723 (3900 5475);
PAINT WHITE (3900 5475);
DISPLAY INVISIBLE (3900 5475);
FORCEPROP 1 LAST PART_NUMBER CS-5602FB01
J 0
(3650 5275);
DISPLAY 0.489362 (3650 5275);
PAINT SKYBLUE (3650 5275);
DISPLAY INVISIBLE (3650 5275);
FORCEADD UNIVERSAL_GND..1
(4325 1250);
FORCEPROP 3 LASTPIN (4325 1300) SIG_NAME GND\g
J 0
(4335 1310);
DISPLAY 0.659574 (4335 1310);
PAINT MONO (4335 1310);
DISPLAY INVISIBLE (4335 1310);
FORCEPROP 2 LAST CDS_LIB pure_quanta_power
J 0
(4325 1250);
DISPLAY INVISIBLE (4325 1250);
FORCEPROP 1 LAST HDL_POWER GND
J 1
(4350 1175);
DISPLAY 0.872340 (4350 1175);
PAINT GREEN (4350 1175);
DISPLAY INVISIBLE (4350 1175);
FORCEPROP 1 LAST PATH I35
J 0
(4400 1250);
DISPLAY 0.872340 (4400 1250);
PAINT AQUA (4400 1250);
DISPLAY INVISIBLE (4400 1250);
FORCEADD Q_RES..2
(4325 1475);
FORCEPROP 1 LAST LOCATION PR223
J 0
(4370 1600);
DISPLAY 0.489362 (4370 1600);
PAINT SKYBLUE (4370 1600);
FORCEPROP 0 LAST $SEC 1
J 0
(4375 1650);
DISPLAY 0.680851 (4375 1650);
PAINT MONO (4375 1650);
DISPLAY INVISIBLE (4375 1650);
FORCEPROP 0 LAST CDS_SEC 1
J 0
(4375 1650);
DISPLAY 1.021277 (4375 1650);
DISPLAY INVISIBLE (4375 1650);
FORCEPROP 1 LASTPIN (4325 1575) $PN 1
J 0
(4330 1537);
DISPLAY 0.489362 (4330 1537);
PAINT MONO (4330 1537);
FORCEPROP 1 LASTPIN (4325 1375) $PN 2
J 0
(4330 1385);
DISPLAY 0.489362 (4330 1385);
PAINT MONO (4330 1385);
FORCEPROP 1 LAST MATERIAL EMPTY
J 0
(4365 1400);
DISPLAY 0.489362 (4365 1400);
PAINT RED (4365 1400);
FORCEPROP 1 LAST WATTAGE 1/8W
J 0
(4365 1450);
DISPLAY 0.489362 (4365 1450);
PAINT SKYBLUE (4365 1450);
FORCEPROP 1 LAST TOLERANCE 1%
J 0
(4370 1500);
DISPLAY 0.489362 (4370 1500);
PAINT SKYBLUE (4370 1500);
FORCEPROP 1 LAST PACK_TYPE 0402LF
J 0
(4365 1300);
DISPLAY 0.489362 (4365 1300);
PAINT SKYBLUE (4365 1300);
FORCEPROP 1 LAST VALUE 1.5
J 0
(4370 1550);
DISPLAY 0.489362 (4370 1550);
PAINT SKYBLUE (4370 1550);
FORCEPROP 2 LAST CDS_LIB pure_quanta
J 0
(4325 1475);
DISPLAY INVISIBLE (4325 1475);
FORCEPROP 1 LAST PATH I36
J 0
(4375 1650);
DISPLAY 0.978723 (4375 1650);
PAINT WHITE (4375 1650);
DISPLAY INVISIBLE (4375 1650);
FORCEPROP 1 LAST PART_NUMBER CS-1504FB00
J 0
(4365 1350);
DISPLAY 0.489362 (4365 1350);
PAINT SKYBLUE (4365 1350);
DISPLAY INVISIBLE (4365 1350);
FORCEADD Q_CAP..1
(4325 1975);
FORCEPROP 1 LAST LOCATION PC159
J 0
(4375 2075);
DISPLAY 0.489362 (4375 2075);
PAINT SKYBLUE (4375 2075);
FORCEPROP 0 LAST $SEC 1
J 0
(4375 2125);
DISPLAY 0.680851 (4375 2125);
PAINT MONO (4375 2125);
DISPLAY INVISIBLE (4375 2125);
FORCEPROP 0 LAST CDS_SEC 1
J 0
(4375 2125);
DISPLAY 1.021277 (4375 2125);
DISPLAY INVISIBLE (4375 2125);
FORCEPROP 1 LASTPIN (4325 2075) $PN 1
J 0
(4335 2055);
DISPLAY 0.489362 (4335 2055);
PAINT MONO (4335 2055);
FORCEPROP 1 LASTPIN (4325 1875) $PN 2
J 0
(4335 1855);
DISPLAY 0.489362 (4335 1855);
PAINT MONO (4335 1855);
FORCEPROP 1 LAST PACK_TYPE C0402
J 0
(4375 1775);
DISPLAY 0.489362 (4375 1775);
PAINT SKYBLUE (4375 1775);
FORCEPROP 1 LAST VOLTAGE 50V
J 0
(4375 1975);
DISPLAY 0.489362 (4375 1975);
PAINT SKYBLUE (4375 1975);
FORCEPROP 1 LAST VALUE 560PF
J 0
(4375 2025);
DISPLAY 0.489362 (4375 2025);
PAINT SKYBLUE (4375 2025);
FORCEPROP 1 LAST TOLERANCE 10%
J 0
(4375 1925);
DISPLAY 0.489362 (4375 1925);
PAINT SKYBLUE (4375 1925);
FORCEPROP 1 LAST MATERIAL EMPTY
J 0
(4375 1875);
DISPLAY 0.489362 (4375 1875);
PAINT RED (4375 1875);
FORCEPROP 2 LAST CDS_LIB pure_quanta
J 0
(4325 1975);
DISPLAY INVISIBLE (4325 1975);
FORCEPROP 1 LAST PATH I37
J 0
(4375 2125);
DISPLAY 0.978723 (4375 2125);
PAINT WHITE (4375 2125);
DISPLAY INVISIBLE (4375 2125);
FORCEPROP 1 LAST PART_NUMBER CH1566K1B09
J 0
(4375 1825);
DISPLAY 0.489362 (4375 1825);
PAINT SKYBLUE (4375 1825);
DISPLAY INVISIBLE (4375 1825);
FORCEADD OFFPAGE..6
(5175 1925);
FORCEPROP 2 LAST $XR0 206 
J 0
(4895 1925);
DISPLAY 0.638298 (4895 1925);
PAINT MONO (4895 1925);
FORCEPROP 2 LAST CDS_LIB standard
J 0
(5175 1925);
DISPLAY INVISIBLE (5175 1925);
FORCEPROP 1 LAST OFFPAGE TRUE
J 0
(5500 1800);
DISPLAY 0.872340 (5500 1800);
PAINT GREEN (5500 1800);
DISPLAY INVISIBLE (5500 1800);
FORCEPROP 1 LAST COMMENT_BODY TRUE
J 0
(5275 1850);
DISPLAY 0.872340 (5275 1850);
PAINT GREEN (5275 1850);
DISPLAY INVISIBLE (5275 1850);
FORCEPROP 2 LAST PATH I38
J 0
(4900 1975);
DISPLAY 0.680851 (4900 1975);
DISPLAY INVISIBLE (4900 1975);
FORCEADD Q_RES..1
(5450 1150);
FORCEPROP 1 LAST LOCATION PR104
J 0
(5425 1200);
DISPLAY 0.489362 (5425 1200);
PAINT SKYBLUE (5425 1200);
FORCEPROP 0 LAST $SEC 1
J 0
(5700 1275);
DISPLAY 0.680851 (5700 1275);
PAINT MONO (5700 1275);
DISPLAY INVISIBLE (5700 1275);
FORCEPROP 0 LAST CDS_SEC 1
J 0
(5700 1275);
DISPLAY 1.021277 (5700 1275);
DISPLAY INVISIBLE (5700 1275);
FORCEPROP 1 LASTPIN (5350 1150) $PN 1
J 0
(5362 1162);
DISPLAY 0.787234 (5362 1162);
PAINT MONO (5362 1162);
DISPLAY INVISIBLE (5362 1162);
FORCEPROP 1 LASTPIN (5550 1150) $PN 2
J 0
(5512 1162);
DISPLAY 0.787234 (5512 1162);
PAINT MONO (5512 1162);
DISPLAY INVISIBLE (5512 1162);
FORCEPROP 1 LAST WATTAGE 1/16W
J 2
(5700 1225);
DISPLAY 0.489362 (5700 1225);
PAINT SKYBLUE (5700 1225);
FORCEPROP 1 LAST MATERIAL CHIP
J 0
(5600 1175);
DISPLAY 0.489362 (5600 1175);
PAINT SKYBLUE (5600 1175);
FORCEPROP 1 LAST TOLERANCE 5%
J 0
(5275 1200);
DISPLAY 0.489362 (5275 1200);
PAINT SKYBLUE (5275 1200);
FORCEPROP 1 LAST VALUE 0
J 2
(5250 1200);
DISPLAY 0.489362 (5250 1200);
PAINT SKYBLUE (5250 1200);
FORCEPROP 1 LAST PACK_TYPE 0402LF
J 0
(5525 1100);
DISPLAY 0.489362 (5525 1100);
PAINT SKYBLUE (5525 1100);
FORCEPROP 2 LAST CDS_LIB pure_quanta
J 0
(5450 1150);
DISPLAY INVISIBLE (5450 1150);
FORCEPROP 1 LAST PATH I39
J 0
(5400 1300);
DISPLAY 0.978723 (5400 1300);
PAINT WHITE (5400 1300);
DISPLAY INVISIBLE (5400 1300);
FORCEPROP 1 LAST PART_NUMBER CS00002JB13
J 0
(5175 1100);
DISPLAY 0.489362 (5175 1100);
PAINT SKYBLUE (5175 1100);
DISPLAY INVISIBLE (5175 1100);
FORCEADD Q_RES..2
R 2
(850 1675);
FORCEPROP 1 LAST LOCATION PR97
J 2
(805 1800);
DISPLAY 0.489362 (805 1800);
PAINT SKYBLUE (805 1800);
FORCEPROP 0 LAST $SEC 1
J 2
(800 1850);
DISPLAY 0.680851 (800 1850);
PAINT MONO (800 1850);
DISPLAY INVISIBLE (800 1850);
FORCEPROP 0 LAST CDS_SEC 1
J 2
(800 1850);
DISPLAY 1.021277 (800 1850);
DISPLAY INVISIBLE (800 1850);
FORCEPROP 1 LASTPIN (850 1775) $PN 1
J 2
(845 1737);
DISPLAY 0.489362 (845 1737);
PAINT MONO (845 1737);
FORCEPROP 1 LASTPIN (850 1575) $PN 2
J 2
(845 1585);
DISPLAY 0.489362 (845 1585);
PAINT MONO (845 1585);
FORCEPROP 1 LAST PACK_TYPE 0402LF
J 2
(800 1500);
DISPLAY 0.489362 (800 1500);
PAINT SKYBLUE (800 1500);
FORCEPROP 1 LAST WATTAGE 1/16W
J 2
(800 1650);
DISPLAY 0.489362 (800 1650);
PAINT SKYBLUE (800 1650);
FORCEPROP 1 LAST MATERIAL EMPTY
J 2
(800 1600);
DISPLAY 0.489362 (800 1600);
PAINT RED (800 1600);
FORCEPROP 1 LAST TOLERANCE 1%
J 2
(795 1700);
DISPLAY 0.489362 (795 1700);
PAINT SKYBLUE (795 1700);
FORCEPROP 1 LAST VALUE 8.87K
J 2
(795 1750);
DISPLAY 0.489362 (795 1750);
PAINT SKYBLUE (795 1750);
FORCEPROP 2 LAST CDS_LIB pure_quanta
J 2
(850 1675);
DISPLAY INVISIBLE (850 1675);
FORCEPROP 1 LAST PATH I4
J 2
(800 1850);
DISPLAY 0.978723 (800 1850);
PAINT WHITE (800 1850);
DISPLAY INVISIBLE (800 1850);
FORCEPROP 1 LAST PART_NUMBER CS28872FB01
J 2
(800 1550);
DISPLAY 0.489362 (800 1550);
PAINT SKYBLUE (800 1550);
DISPLAY INVISIBLE (800 1550);
FORCEADD Q_INDUCTOR4P_14..1
(6225 2050);
FORCEPROP 1 LAST LOCATION PL18
J 0
(5900 2225);
DISPLAY 0.489362 (5900 2225);
PAINT SKYBLUE (5900 2225);
FORCEPROP 0 LAST $SEC 1
J 0
(6275 2250);
DISPLAY 0.680851 (6275 2250);
PAINT MONO (6275 2250);
DISPLAY INVISIBLE (6275 2250);
FORCEPROP 0 LAST CDS_SEC 1
J 0
(6275 2250);
DISPLAY 1.021277 (6275 2250);
DISPLAY INVISIBLE (6275 2250);
FORCEPROP 0 LASTPIN (5825 2175) $PN 1
J 2
(5815 2185);
DISPLAY 0.489362 (5815 2185);
PAINT MONO (5815 2185);
FORCEPROP 0 LASTPIN (5825 1925) $PN 2
J 2
(5815 1935);
DISPLAY 0.489362 (5815 1935);
PAINT MONO (5815 1935);
FORCEPROP 0 LASTPIN (6625 1925) $PN 3
J 0
(6635 1935);
DISPLAY 0.489362 (6635 1935);
PAINT MONO (6635 1935);
FORCEPROP 0 LASTPIN (6625 2175) $PN 4
J 0
(6635 2185);
DISPLAY 0.489362 (6635 2185);
PAINT MONO (6635 2185);
FORCEPROP 2 LAST VALUE 150NH
J 0
(6125 2225);
DISPLAY 0.489362 (6125 2225);
PAINT SKYBLUE (6125 2225);
FORCEPROP 1 LAST MATERIAL IND
J 0
(6025 2225);
DISPLAY 0.489362 (6025 2225);
PAINT SKYBLUE (6025 2225);
FORCEPROP 2 LAST PART_TYPE SMLF
J 0
(6150 1800);
DISPLAY 1.021277 (6150 1800);
FORCEPROP 1 LAST NEEDS_NO_SIZE TRUE
J 0
(6225 2050);
DISPLAY 0.468085 (6225 2050);
PAINT GREEN (6225 2050);
DISPLAY INVISIBLE (6225 2050);
FORCEPROP 2 LAST CDS_LIB pure_quanta
J 0
(6225 2050);
DISPLAY INVISIBLE (6225 2050);
FORCEPROP 1 LAST PATH I40
J 0
(6425 2205);
DISPLAY 0.723404 (6425 2205);
PAINT GREEN (6425 2205);
DISPLAY INVISIBLE (6425 2205);
FORCEPROP 1 LAST PART_NUMBER CV+15^0TZ04
J 0
(6275 2225);
DISPLAY 0.489362 (6275 2225);
PAINT SKYBLUE (6275 2225);
DISPLAY INVISIBLE (6275 2225);
FORCEADD Q_CAP..1
(4850 2400);
FORCEPROP 1 LAST LOCATION PC156
J 0
(4900 2500);
DISPLAY 0.489362 (4900 2500);
PAINT SKYBLUE (4900 2500);
FORCEPROP 0 LAST $SEC 1
J 0
(4900 2550);
DISPLAY 0.680851 (4900 2550);
PAINT MONO (4900 2550);
DISPLAY INVISIBLE (4900 2550);
FORCEPROP 0 LAST CDS_SEC 1
J 2
(4900 2525);
DISPLAY 1.021277 (4900 2525);
DISPLAY INVISIBLE (4900 2525);
FORCEPROP 1 LASTPIN (4850 2500) $PN 1
J 0
(4860 2480);
DISPLAY 0.489362 (4860 2480);
PAINT MONO (4860 2480);
FORCEPROP 1 LASTPIN (4850 2300) $PN 2
J 0
(4860 2280);
DISPLAY 0.489362 (4860 2280);
PAINT MONO (4860 2280);
FORCEPROP 1 LAST VOLTAGE 16V
J 0
(4900 2400);
DISPLAY 0.489362 (4900 2400);
PAINT SKYBLUE (4900 2400);
FORCEPROP 1 LAST VALUE 0.22UF
J 0
(4900 2450);
DISPLAY 0.489362 (4900 2450);
PAINT SKYBLUE (4900 2450);
FORCEPROP 1 LAST TOLERANCE 10%
J 0
(4900 2350);
DISPLAY 0.489362 (4900 2350);
PAINT SKYBLUE (4900 2350);
FORCEPROP 1 LAST MATERIAL X7R
J 0
(4900 2300);
DISPLAY 0.489362 (4900 2300);
PAINT SKYBLUE (4900 2300);
FORCEPROP 1 LAST PACK_TYPE 0402
J 0
(4900 2200);
DISPLAY 0.489362 (4900 2200);
PAINT SKYBLUE (4900 2200);
FORCEPROP 2 LAST CDS_LIB pure_quanta
J 2
(4850 2400);
DISPLAY INVISIBLE (4850 2400);
FORCEPROP 1 LAST PATH I41
J 0
(4900 2550);
DISPLAY 0.978723 (4900 2550);
PAINT WHITE (4900 2550);
DISPLAY INVISIBLE (4900 2550);
FORCEPROP 1 LAST PART_NUMBER CH4223K1B00
J 0
(4900 2250);
DISPLAY 0.489362 (4900 2250);
PAINT SKYBLUE (4900 2250);
DISPLAY INVISIBLE (4900 2250);
FORCEADD Q_CAP..1
(4175 3100);
FORCEPROP 1 LAST LOCATION PC151_2
J 0
(4225 3250);
DISPLAY 0.489362 (4225 3250);
PAINT SKYBLUE (4225 3250);
FORCEPROP 0 LAST $SEC 1
J 0
(4225 3300);
DISPLAY 0.680851 (4225 3300);
PAINT MONO (4225 3300);
DISPLAY INVISIBLE (4225 3300);
FORCEPROP 0 LAST CDS_SEC 1
J 0
(4225 3300);
DISPLAY 1.021277 (4225 3300);
DISPLAY INVISIBLE (4225 3300);
FORCEPROP 1 LASTPIN (4175 3200) $PN 1
J 0
(4185 3180);
DISPLAY 0.489362 (4185 3180);
PAINT MONO (4185 3180);
FORCEPROP 1 LASTPIN (4175 3000) $PN 2
J 0
(4185 2980);
DISPLAY 0.489362 (4185 2980);
PAINT MONO (4185 2980);
FORCEPROP 1 LAST PACK_TYPE C0402
J 0
(4225 3000);
DISPLAY 0.489362 (4225 3000);
PAINT SKYBLUE (4225 3000);
FORCEPROP 1 LAST VOLTAGE 25V
J 0
(4225 3150);
DISPLAY 0.489362 (4225 3150);
PAINT SKYBLUE (4225 3150);
FORCEPROP 1 LAST VALUE 1UF
J 0
(4225 3200);
DISPLAY 0.489362 (4225 3200);
PAINT SKYBLUE (4225 3200);
FORCEPROP 1 LAST TOLERANCE 10%
J 0
(4225 3100);
DISPLAY 0.489362 (4225 3100);
PAINT SKYBLUE (4225 3100);
FORCEPROP 1 LAST MATERIAL X6S
J 0
(4225 3050);
DISPLAY 0.489362 (4225 3050);
PAINT SKYBLUE (4225 3050);
FORCEPROP 2 LAST CDS_LIB pure_quanta
J 0
(4175 3100);
DISPLAY INVISIBLE (4175 3100);
FORCEPROP 1 LAST PATH I42
J 0
(4225 3250);
DISPLAY 0.978723 (4225 3250);
PAINT WHITE (4225 3250);
DISPLAY INVISIBLE (4225 3250);
FORCEPROP 1 LAST PART_NUMBER CH5104KEB02
J 0
(4225 2950);
DISPLAY 0.489362 (4225 2950);
PAINT SKYBLUE (4225 2950);
DISPLAY INVISIBLE (4225 2950);
FORCEADD Q_CAP..1
(4575 3100);
FORCEPROP 1 LAST LOCATION PC153_2
J 0
(4625 3250);
DISPLAY 0.489362 (4625 3250);
PAINT SKYBLUE (4625 3250);
FORCEPROP 0 LAST $SEC 1
J 0
(4625 3300);
DISPLAY 0.680851 (4625 3300);
PAINT MONO (4625 3300);
DISPLAY INVISIBLE (4625 3300);
FORCEPROP 0 LAST CDS_SEC 1
J 0
(4625 3300);
DISPLAY 1.021277 (4625 3300);
DISPLAY INVISIBLE (4625 3300);
FORCEPROP 1 LASTPIN (4575 3200) $PN 1
J 0
(4585 3180);
DISPLAY 0.489362 (4585 3180);
PAINT MONO (4585 3180);
FORCEPROP 1 LASTPIN (4575 3000) $PN 2
J 0
(4585 2980);
DISPLAY 0.489362 (4585 2980);
PAINT MONO (4585 2980);
FORCEPROP 1 LAST PACK_TYPE C0805
J 0
(4625 3000);
DISPLAY 0.489362 (4625 3000);
PAINT SKYBLUE (4625 3000);
FORCEPROP 1 LAST MATERIAL X6S
J 0
(4625 3050);
DISPLAY 0.489362 (4625 3050);
PAINT SKYBLUE (4625 3050);
FORCEPROP 1 LAST TOLERANCE 20%
J 0
(4625 3100);
DISPLAY 0.489362 (4625 3100);
PAINT SKYBLUE (4625 3100);
FORCEPROP 1 LAST VOLTAGE 16V
J 0
(4625 3150);
DISPLAY 0.489362 (4625 3150);
PAINT SKYBLUE (4625 3150);
FORCEPROP 1 LAST VALUE 22UF
J 0
(4625 3200);
DISPLAY 0.489362 (4625 3200);
PAINT SKYBLUE (4625 3200);
FORCEPROP 2 LAST CDS_LIB pure_quanta
J 0
(4575 3100);
DISPLAY INVISIBLE (4575 3100);
FORCEPROP 1 LAST PATH I43
J 0
(4625 3250);
DISPLAY 0.978723 (4625 3250);
PAINT WHITE (4625 3250);
DISPLAY INVISIBLE (4625 3250);
FORCEPROP 1 LAST PART_NUMBER CH6223MEA01
J 0
(4625 2950);
DISPLAY 0.489362 (4625 2950);
PAINT SKYBLUE (4625 2950);
DISPLAY INVISIBLE (4625 2950);
FORCEADD UNIVERSAL_GND..1
(4325 4000);
FORCEPROP 3 LASTPIN (4325 4050) SIG_NAME GND\g
J 0
(4335 4060);
DISPLAY 0.659574 (4335 4060);
PAINT MONO (4335 4060);
DISPLAY INVISIBLE (4335 4060);
FORCEPROP 2 LAST CDS_LIB pure_quanta_power
J 0
(4325 4000);
DISPLAY INVISIBLE (4325 4000);
FORCEPROP 1 LAST HDL_POWER GND
J 1
(4350 3925);
DISPLAY 0.872340 (4350 3925);
PAINT GREEN (4350 3925);
DISPLAY INVISIBLE (4350 3925);
FORCEPROP 1 LAST PATH I44
J 0
(4400 4000);
DISPLAY 0.872340 (4400 4000);
PAINT AQUA (4400 4000);
DISPLAY INVISIBLE (4400 4000);
FORCEADD Q_CAP..1
(4975 3100);
FORCEPROP 1 LAST LOCATION PC157_2
J 0
(5025 3250);
DISPLAY 0.489362 (5025 3250);
PAINT SKYBLUE (5025 3250);
FORCEPROP 0 LAST $SEC 1
J 0
(5025 3300);
DISPLAY 0.680851 (5025 3300);
PAINT MONO (5025 3300);
DISPLAY INVISIBLE (5025 3300);
FORCEPROP 0 LAST CDS_SEC 1
J 0
(5025 3300);
DISPLAY 1.021277 (5025 3300);
DISPLAY INVISIBLE (5025 3300);
FORCEPROP 1 LASTPIN (4975 3200) $PN 1
J 0
(4985 3180);
DISPLAY 0.489362 (4985 3180);
PAINT MONO (4985 3180);
FORCEPROP 1 LASTPIN (4975 3000) $PN 2
J 0
(4985 2980);
DISPLAY 0.489362 (4985 2980);
PAINT MONO (4985 2980);
FORCEPROP 1 LAST TOLERANCE 20%
J 0
(5025 3100);
DISPLAY 0.489362 (5025 3100);
PAINT SKYBLUE (5025 3100);
FORCEPROP 1 LAST VOLTAGE 16V
J 0
(5025 3150);
DISPLAY 0.489362 (5025 3150);
PAINT SKYBLUE (5025 3150);
FORCEPROP 1 LAST VALUE 22UF
J 0
(5025 3200);
DISPLAY 0.489362 (5025 3200);
PAINT SKYBLUE (5025 3200);
FORCEPROP 1 LAST MATERIAL X6S
J 0
(5025 3050);
DISPLAY 0.489362 (5025 3050);
PAINT SKYBLUE (5025 3050);
FORCEPROP 1 LAST PACK_TYPE C0805
J 0
(5025 3000);
DISPLAY 0.489362 (5025 3000);
PAINT SKYBLUE (5025 3000);
FORCEPROP 2 LAST CDS_LIB pure_quanta
J 0
(4975 3100);
DISPLAY INVISIBLE (4975 3100);
FORCEPROP 1 LAST PATH I45
J 0
(5025 3250);
DISPLAY 0.978723 (5025 3250);
PAINT WHITE (5025 3250);
DISPLAY INVISIBLE (5025 3250);
FORCEPROP 1 LAST PART_NUMBER CH6223MEA01
J 0
(5025 2950);
DISPLAY 0.489362 (5025 2950);
PAINT SKYBLUE (5025 2950);
DISPLAY INVISIBLE (5025 2950);
FORCEADD UNIVERSAL_GND..1
(5450 2750);
FORCEPROP 3 LASTPIN (5450 2800) SIG_NAME GND\g
J 0
(5460 2810);
DISPLAY 0.659574 (5460 2810);
PAINT MONO (5460 2810);
DISPLAY INVISIBLE (5460 2810);
FORCEPROP 2 LAST CDS_LIB pure_quanta_power
J 0
(5450 2750);
PAINT MONO (5450 2750);
DISPLAY INVISIBLE (5450 2750);
FORCEPROP 1 LAST HDL_POWER GND
J 1
(5475 2675);
DISPLAY 0.872340 (5475 2675);
PAINT GREEN (5475 2675);
DISPLAY INVISIBLE (5475 2675);
FORCEPROP 1 LAST PATH I46
J 0
(5525 2750);
DISPLAY 0.872340 (5525 2750);
PAINT AQUA (5525 2750);
DISPLAY INVISIBLE (5525 2750);
FORCEADD Q_CAP..1
(5450 3100);
FORCEPROP 1 LAST LOCATION PC159_2
J 0
(5525 3250);
DISPLAY 0.489362 (5525 3250);
PAINT SKYBLUE (5525 3250);
FORCEPROP 0 LAST $SEC 1
J 0
(5500 3250);
DISPLAY 0.680851 (5500 3250);
PAINT MONO (5500 3250);
DISPLAY INVISIBLE (5500 3250);
FORCEPROP 0 LAST CDS_SEC 1
J 0
(5500 3250);
DISPLAY 1.021277 (5500 3250);
DISPLAY INVISIBLE (5500 3250);
FORCEPROP 1 LASTPIN (5450 3200) $PN 1
J 0
(5460 3180);
DISPLAY 0.489362 (5460 3180);
PAINT MONO (5460 3180);
FORCEPROP 1 LASTPIN (5450 3000) $PN 2
J 0
(5460 2980);
DISPLAY 0.489362 (5460 2980);
PAINT MONO (5460 2980);
FORCEPROP 1 LAST TOLERANCE 20%
J 0
(5525 3100);
DISPLAY 0.489362 (5525 3100);
PAINT SKYBLUE (5525 3100);
FORCEPROP 1 LAST VOLTAGE 16V
J 0
(5525 3150);
DISPLAY 0.489362 (5525 3150);
PAINT SKYBLUE (5525 3150);
FORCEPROP 1 LAST VALUE 22UF
J 0
(5525 3200);
DISPLAY 0.489362 (5525 3200);
PAINT SKYBLUE (5525 3200);
FORCEPROP 1 LAST MATERIAL X6S
J 0
(5525 3050);
DISPLAY 0.489362 (5525 3050);
PAINT SKYBLUE (5525 3050);
FORCEPROP 1 LAST PACK_TYPE C0805
J 0
(5525 3000);
DISPLAY 0.489362 (5525 3000);
PAINT SKYBLUE (5525 3000);
FORCEPROP 2 LAST CDS_LIB pure_quanta
J 0
(5450 3100);
DISPLAY INVISIBLE (5450 3100);
FORCEPROP 1 LAST PATH I47
J 0
(5500 3250);
DISPLAY 0.978723 (5500 3250);
PAINT WHITE (5500 3250);
DISPLAY INVISIBLE (5500 3250);
FORCEPROP 1 LAST PART_NUMBER CH6223MEA01
J 0
(5525 2950);
DISPLAY 0.489362 (5525 2950);
PAINT SKYBLUE (5525 2950);
DISPLAY INVISIBLE (5525 2950);
FORCEADD VCC_CORE..1
(5450 3475);
FORCEPROP 3 LASTPIN (5450 3425) SIG_NAME SW_P12V_AUX_PVDDIO_P0_FLT\g
J 0
(5460 3435);
DISPLAY 0.659574 (5460 3435);
PAINT MONO (5460 3435);
DISPLAY INVISIBLE (5460 3435);
FORCEPROP 1 LAST HDL_POWER SW_P12V_AUX_PVDDIO_P0_FLT
J 1
(5450 3525);
DISPLAY 0.489362 (5450 3525);
PAINT GREEN (5450 3525);
FORCEPROP 2 LAST CDS_LIB pure_quanta_power
J 0
(5450 3475);
DISPLAY INVISIBLE (5450 3475);
FORCEPROP 1 LAST PATH I48
J 0
(5500 3500);
DISPLAY 0.872340 (5500 3500);
PAINT AQUA (5500 3500);
DISPLAY INVISIBLE (5500 3500);
FORCEADD Q_RES..1
(5450 3875);
FORCEPROP 1 LAST LOCATION PR103
J 0
(5425 3900);
DISPLAY 0.489362 (5425 3900);
PAINT SKYBLUE (5425 3900);
FORCEPROP 0 LAST $SEC 1
J 0
(5700 4000);
DISPLAY 0.680851 (5700 4000);
PAINT MONO (5700 4000);
DISPLAY INVISIBLE (5700 4000);
FORCEPROP 0 LAST CDS_SEC 1
J 0
(5700 4000);
DISPLAY 1.021277 (5700 4000);
DISPLAY INVISIBLE (5700 4000);
FORCEPROP 1 LASTPIN (5350 3875) $PN 1
J 0
(5362 3887);
DISPLAY 0.787234 (5362 3887);
PAINT MONO (5362 3887);
DISPLAY INVISIBLE (5362 3887);
FORCEPROP 1 LASTPIN (5550 3875) $PN 2
J 0
(5512 3887);
DISPLAY 0.787234 (5512 3887);
PAINT MONO (5512 3887);
DISPLAY INVISIBLE (5512 3887);
FORCEPROP 1 LAST PACK_TYPE 0402LF
J 0
(5550 3825);
DISPLAY 0.489362 (5550 3825);
PAINT SKYBLUE (5550 3825);
FORCEPROP 1 LAST MATERIAL CHIP
J 0
(5600 3900);
DISPLAY 0.489362 (5600 3900);
PAINT SKYBLUE (5600 3900);
FORCEPROP 1 LAST TOLERANCE 5%
J 0
(5275 3925);
DISPLAY 0.489362 (5275 3925);
PAINT SKYBLUE (5275 3925);
FORCEPROP 1 LAST VALUE 0
J 2
(5250 3925);
DISPLAY 0.489362 (5250 3925);
PAINT SKYBLUE (5250 3925);
FORCEPROP 1 LAST WATTAGE 1/16W
J 2
(5700 3950);
DISPLAY 0.489362 (5700 3950);
PAINT SKYBLUE (5700 3950);
FORCEPROP 2 LAST CDS_LIB pure_quanta
J 0
(5450 3875);
DISPLAY INVISIBLE (5450 3875);
FORCEPROP 1 LAST PATH I49
J 0
(5400 4025);
DISPLAY 0.978723 (5400 4025);
PAINT WHITE (5400 4025);
DISPLAY INVISIBLE (5400 4025);
FORCEPROP 1 LAST PART_NUMBER CS00002JB13
J 0
(5150 3825);
DISPLAY 0.489362 (5150 3825);
PAINT SKYBLUE (5150 3825);
DISPLAY INVISIBLE (5150 3825);
FORCEADD OFFPAGE..1
(1300 1575);
FORCEPROP 2 LAST $XR0 200 
J 0
(1018 1575);
DISPLAY 0.638298 (1018 1575);
PAINT MONO (1018 1575);
FORCEPROP 2 LAST CDS_LIB standard
J 0
(1300 1575);
DISPLAY INVISIBLE (1300 1575);
FORCEPROP 1 LAST OFFPAGE TRUE
J 0
(1625 1450);
DISPLAY 0.872340 (1625 1450);
PAINT GREEN (1625 1450);
DISPLAY INVISIBLE (1625 1450);
FORCEPROP 1 LAST COMMENT_BODY TRUE
J 0
(1425 1475);
DISPLAY 0.872340 (1425 1475);
PAINT GREEN (1425 1475);
DISPLAY INVISIBLE (1425 1475);
FORCEPROP 2 LAST PATH I5
J 0
(1050 1625);
DISPLAY 0.680851 (1050 1625);
DISPLAY INVISIBLE (1050 1625);
FORCEADD OFFPAGE..3
(7075 1925);
FORCEPROP 2 LAST $XR0 205 
J 0
(7319 1925);
DISPLAY 0.638298 (7319 1925);
PAINT MONO (7319 1925);
FORCEPROP 2 LAST CDS_LIB standard
J 0
(7075 1925);
DISPLAY INVISIBLE (7075 1925);
FORCEPROP 1 LAST OFFPAGE TRUE
J 0
(7400 1800);
DISPLAY 0.872340 (7400 1800);
PAINT GREEN (7400 1800);
DISPLAY INVISIBLE (7400 1800);
FORCEPROP 1 LAST COMMENT_BODY TRUE
J 0
(7025 1825);
DISPLAY 0.872340 (7025 1825);
PAINT GREEN (7025 1825);
DISPLAY INVISIBLE (7025 1825);
FORCEPROP 2 LAST PATH I50
J 0
(7325 1975);
DISPLAY 0.680851 (7325 1975);
DISPLAY INVISIBLE (7325 1975);
FORCEADD Q_CAP..1
(7650 1975);
FORCEPROP 1 LAST LOCATION PC168_2
J 0
(7700 2100);
DISPLAY 0.489362 (7700 2100);
PAINT SKYBLUE (7700 2100);
FORCEPROP 0 LAST $SEC 1
J 0
(7700 2150);
DISPLAY 0.680851 (7700 2150);
PAINT MONO (7700 2150);
DISPLAY INVISIBLE (7700 2150);
FORCEPROP 0 LAST CDS_SEC 1
J 0
(7700 2150);
DISPLAY 1.021277 (7700 2150);
DISPLAY INVISIBLE (7700 2150);
FORCEPROP 1 LASTPIN (7650 2075) $PN 1
J 0
(7660 2055);
DISPLAY 0.489362 (7660 2055);
PAINT MONO (7660 2055);
FORCEPROP 1 LASTPIN (7650 1875) $PN 2
J 0
(7660 1855);
DISPLAY 0.489362 (7660 1855);
PAINT MONO (7660 1855);
FORCEPROP 1 LAST PACK_TYPE C0805
J 0
(7700 1850);
DISPLAY 0.489362 (7700 1850);
PAINT SKYBLUE (7700 1850);
FORCEPROP 1 LAST MATERIAL X6S
J 0
(7700 1900);
DISPLAY 0.489362 (7700 1900);
PAINT SKYBLUE (7700 1900);
FORCEPROP 1 LAST TOLERANCE 20%
J 0
(7700 1950);
DISPLAY 0.489362 (7700 1950);
PAINT SKYBLUE (7700 1950);
FORCEPROP 1 LAST VALUE 22UF
J 0
(7700 2050);
DISPLAY 0.489362 (7700 2050);
PAINT SKYBLUE (7700 2050);
FORCEPROP 1 LAST VOLTAGE 4V
J 0
(7700 2000);
DISPLAY 0.489362 (7700 2000);
PAINT SKYBLUE (7700 2000);
FORCEPROP 2 LAST CDS_LIB pure_quanta
J 0
(7650 1975);
DISPLAY INVISIBLE (7650 1975);
FORCEPROP 1 LAST PATH I51
J 0
(7700 2125);
DISPLAY 0.978723 (7700 2125);
PAINT WHITE (7700 2125);
DISPLAY INVISIBLE (7700 2125);
FORCEPROP 1 LAST PART_NUMBER CH622KMEA03
J 0
(7700 1800);
DISPLAY 0.489362 (7700 1800);
PAINT SKYBLUE (7700 1800);
DISPLAY INVISIBLE (7700 1800);
FORCEADD UNIVERSAL_GND..1
(8075 1625);
FORCEPROP 3 LASTPIN (8075 1675) SIG_NAME GND\g
J 0
(8085 1685);
DISPLAY 0.659574 (8085 1685);
PAINT MONO (8085 1685);
DISPLAY INVISIBLE (8085 1685);
FORCEPROP 2 LAST CDS_LIB pure_quanta_power
J 0
(8075 1625);
PAINT MONO (8075 1625);
DISPLAY INVISIBLE (8075 1625);
FORCEPROP 1 LAST HDL_POWER GND
J 1
(8100 1550);
DISPLAY 0.872340 (8100 1550);
PAINT GREEN (8100 1550);
DISPLAY INVISIBLE (8100 1550);
FORCEPROP 1 LAST PATH I52
J 0
(8150 1625);
DISPLAY 0.872340 (8150 1625);
PAINT AQUA (8150 1625);
DISPLAY INVISIBLE (8150 1625);
FORCEADD Q_CAP..1
(8075 1975);
FORCEPROP 1 LAST LOCATION PC170_2
J 0
(8125 2100);
DISPLAY 0.489362 (8125 2100);
PAINT SKYBLUE (8125 2100);
FORCEPROP 0 LAST $SEC 1
J 0
(8125 2150);
DISPLAY 0.680851 (8125 2150);
PAINT MONO (8125 2150);
DISPLAY INVISIBLE (8125 2150);
FORCEPROP 0 LAST CDS_SEC 1
J 0
(8125 2150);
DISPLAY 1.021277 (8125 2150);
DISPLAY INVISIBLE (8125 2150);
FORCEPROP 1 LASTPIN (8075 2075) $PN 1
J 0
(8085 2055);
DISPLAY 0.489362 (8085 2055);
PAINT MONO (8085 2055);
FORCEPROP 1 LASTPIN (8075 1875) $PN 2
J 0
(8085 1855);
DISPLAY 0.489362 (8085 1855);
PAINT MONO (8085 1855);
FORCEPROP 1 LAST PACK_TYPE C0805
J 0
(8125 1850);
DISPLAY 0.489362 (8125 1850);
PAINT SKYBLUE (8125 1850);
FORCEPROP 1 LAST MATERIAL X6S
J 0
(8125 1900);
DISPLAY 0.489362 (8125 1900);
PAINT SKYBLUE (8125 1900);
FORCEPROP 1 LAST TOLERANCE 20%
J 0
(8125 1950);
DISPLAY 0.489362 (8125 1950);
PAINT SKYBLUE (8125 1950);
FORCEPROP 1 LAST VALUE 22UF
J 0
(8125 2050);
DISPLAY 0.489362 (8125 2050);
PAINT SKYBLUE (8125 2050);
FORCEPROP 1 LAST VOLTAGE 4V
J 0
(8125 2000);
DISPLAY 0.489362 (8125 2000);
PAINT SKYBLUE (8125 2000);
FORCEPROP 2 LAST CDS_LIB pure_quanta
J 0
(8075 1975);
DISPLAY INVISIBLE (8075 1975);
FORCEPROP 1 LAST PATH I53
J 0
(8125 2125);
DISPLAY 0.978723 (8125 2125);
PAINT WHITE (8125 2125);
DISPLAY INVISIBLE (8125 2125);
FORCEPROP 1 LAST PART_NUMBER CH622KMEA03
J 0
(8125 1800);
DISPLAY 0.489362 (8125 1800);
PAINT SKYBLUE (8125 1800);
DISPLAY INVISIBLE (8125 1800);
FORCEADD Q_CAPP..1
(7150 3175);
FORCEPROP 1 LAST LOCATION PC160
J 0
(7200 3325);
DISPLAY 0.489362 (7200 3325);
PAINT SKYBLUE (7200 3325);
FORCEPROP 0 LAST $SEC 1
J 0
(7200 3350);
DISPLAY 0.680851 (7200 3350);
PAINT MONO (7200 3350);
DISPLAY INVISIBLE (7200 3350);
FORCEPROP 0 LAST CDS_SEC 1
J 0
(7200 3350);
DISPLAY 1.021277 (7200 3350);
DISPLAY INVISIBLE (7200 3350);
FORCEPROP 1 LASTPIN (7150 3275) $PN 1
J 0
(7160 3260);
DISPLAY 0.489362 (7160 3260);
PAINT MONO (7160 3260);
FORCEPROP 1 LASTPIN (7150 3075) $PN 2
J 0
(7160 3060);
DISPLAY 0.489362 (7160 3060);
PAINT MONO (7160 3060);
FORCEPROP 1 LAST VOLTAGE 2.5V
J 0
(7200 3175);
DISPLAY 0.489362 (7200 3175);
PAINT SKYBLUE (7200 3175);
FORCEPROP 1 LAST VALUE 470UF
J 0
(7200 3275);
DISPLAY 0.489362 (7200 3275);
PAINT SKYBLUE (7200 3275);
FORCEPROP 1 LAST TOLERANCE 20%
J 0
(7200 3225);
DISPLAY 0.489362 (7200 3225);
PAINT SKYBLUE (7200 3225);
FORCEPROP 1 LAST MATERIAL EMPTY
J 0
(7200 3125);
DISPLAY 0.489362 (7200 3125);
PAINT RED (7200 3125);
FORCEPROP 1 LAST PACK_TYPE SMLF
J 0
(7200 3075);
DISPLAY 0.489362 (7200 3075);
PAINT SKYBLUE (7200 3075);
FORCEPROP 2 LAST CDS_LIB pure_quanta
J 0
(7150 3175);
DISPLAY INVISIBLE (7150 3175);
FORCEPROP 1 LAST PATH I54
J 0
(7200 3325);
DISPLAY 0.978723 (7200 3325);
DISPLAY INVISIBLE (7200 3325);
FORCEPROP 1 LAST PART_NUMBER CH747LM8825
J 0
(7200 3025);
DISPLAY 0.489362 (7200 3025);
PAINT SKYBLUE (7200 3025);
DISPLAY INVISIBLE (7200 3025);
FORCEADD VCC_CORE..1
(8075 2325);
FORCEPROP 3 LASTPIN (8075 2275) SIG_NAME PVDDIO_P0\g
J 0
(8085 2285);
DISPLAY 0.659574 (8085 2285);
PAINT MONO (8085 2285);
DISPLAY INVISIBLE (8085 2285);
FORCEPROP 1 LAST HDL_POWER PVDDIO_P0
J 1
(8075 2375);
DISPLAY 0.489362 (8075 2375);
PAINT GREEN (8075 2375);
FORCEPROP 2 LAST CDS_LIB pure_quanta_power
J 0
(8075 2325);
DISPLAY INVISIBLE (8075 2325);
FORCEPROP 1 LAST PATH I55
J 0
(8125 2350);
DISPLAY 0.872340 (8125 2350);
PAINT AQUA (8125 2350);
DISPLAY INVISIBLE (8125 2350);
FORCEADD UNIVERSAL_GND..1
(7950 2825);
FORCEPROP 3 LASTPIN (7950 2875) SIG_NAME GND\g
J 0
(7960 2885);
DISPLAY 0.659574 (7960 2885);
PAINT MONO (7960 2885);
DISPLAY INVISIBLE (7960 2885);
FORCEPROP 2 LAST CDS_LIB pure_quanta_power
J 0
(7950 2825);
PAINT MONO (7950 2825);
DISPLAY INVISIBLE (7950 2825);
FORCEPROP 1 LAST HDL_POWER GND
J 1
(7975 2750);
DISPLAY 0.872340 (7975 2750);
PAINT GREEN (7975 2750);
DISPLAY INVISIBLE (7975 2750);
FORCEPROP 1 LAST PATH I56
J 0
(8025 2825);
DISPLAY 0.872340 (8025 2825);
PAINT AQUA (8025 2825);
DISPLAY INVISIBLE (8025 2825);
FORCEADD Q_CAPP..1
(7550 3175);
FORCEPROP 1 LAST LOCATION PC162
J 0
(7600 3325);
DISPLAY 0.489362 (7600 3325);
PAINT SKYBLUE (7600 3325);
FORCEPROP 0 LAST $SEC 1
J 0
(7600 3375);
DISPLAY 0.680851 (7600 3375);
PAINT MONO (7600 3375);
DISPLAY INVISIBLE (7600 3375);
FORCEPROP 0 LAST CDS_SEC 1
J 0
(7600 3375);
DISPLAY 1.021277 (7600 3375);
DISPLAY INVISIBLE (7600 3375);
FORCEPROP 1 LASTPIN (7550 3275) $PN 1
J 0
(7560 3260);
DISPLAY 0.489362 (7560 3260);
PAINT MONO (7560 3260);
FORCEPROP 1 LASTPIN (7550 3075) $PN 2
J 0
(7560 3060);
DISPLAY 0.489362 (7560 3060);
PAINT MONO (7560 3060);
FORCEPROP 1 LAST MATERIAL SPCAP
J 0
(7600 3125);
DISPLAY 0.489362 (7600 3125);
PAINT SKYBLUE (7600 3125);
FORCEPROP 1 LAST TOLERANCE 20%
J 0
(7600 3225);
DISPLAY 0.489362 (7600 3225);
PAINT SKYBLUE (7600 3225);
FORCEPROP 1 LAST VALUE 470UF
J 0
(7600 3275);
DISPLAY 0.489362 (7600 3275);
PAINT SKYBLUE (7600 3275);
FORCEPROP 1 LAST VOLTAGE 2.5V
J 0
(7600 3175);
DISPLAY 0.489362 (7600 3175);
PAINT SKYBLUE (7600 3175);
FORCEPROP 1 LAST PACK_TYPE SMLF
J 0
(7600 3075);
DISPLAY 0.489362 (7600 3075);
PAINT SKYBLUE (7600 3075);
FORCEPROP 2 LAST CDS_LIB pure_quanta
J 0
(7550 3175);
DISPLAY INVISIBLE (7550 3175);
FORCEPROP 1 LAST PATH I57
J 0
(7600 3325);
DISPLAY 0.978723 (7600 3325);
DISPLAY INVISIBLE (7600 3325);
FORCEPROP 1 LAST PART_NUMBER CH747LM8825
J 0
(7600 3025);
DISPLAY 0.489362 (7600 3025);
PAINT SKYBLUE (7600 3025);
DISPLAY INVISIBLE (7600 3025);
FORCEADD Q_CAPP..1
(7950 3175);
FORCEPROP 1 LAST LOCATION PC165
J 0
(8025 3325);
DISPLAY 0.489362 (8025 3325);
PAINT SKYBLUE (8025 3325);
FORCEPROP 2 LAST $SEC 1
J 0
(8000 3375);
DISPLAY 0.680851 (8000 3375);
PAINT MONO (8000 3375);
DISPLAY INVISIBLE (8000 3375);
FORCEPROP 2 LAST CDS_SEC 1
J 0
(8000 3375);
DISPLAY 1.021277 (8000 3375);
DISPLAY INVISIBLE (8000 3375);
FORCEPROP 1 LASTPIN (7950 3275) $PN 1
J 0
(7960 3260);
DISPLAY 0.489362 (7960 3260);
PAINT MONO (7960 3260);
FORCEPROP 1 LASTPIN (7950 3075) $PN 2
J 0
(7960 3060);
DISPLAY 0.489362 (7960 3060);
PAINT MONO (7960 3060);
FORCEPROP 1 LAST PACK_TYPE SMLF
J 0
(8025 3075);
DISPLAY 0.489362 (8025 3075);
PAINT SKYBLUE (8025 3075);
FORCEPROP 1 LAST VOLTAGE 2.5V
J 0
(8025 3175);
DISPLAY 0.489362 (8025 3175);
PAINT SKYBLUE (8025 3175);
FORCEPROP 1 LAST VALUE 470UF
J 0
(8025 3275);
DISPLAY 0.489362 (8025 3275);
PAINT SKYBLUE (8025 3275);
FORCEPROP 1 LAST TOLERANCE 20%
J 0
(8025 3225);
DISPLAY 0.489362 (8025 3225);
PAINT SKYBLUE (8025 3225);
FORCEPROP 1 LAST MATERIAL SPCAP
J 0
(8025 3125);
DISPLAY 0.489362 (8025 3125);
PAINT SKYBLUE (8025 3125);
FORCEPROP 2 LAST CDS_LIB pure_quanta
J 0
(7950 3175);
DISPLAY INVISIBLE (7950 3175);
FORCEPROP 1 LAST PATH I58
J 0
(8000 3325);
DISPLAY 0.978723 (8000 3325);
DISPLAY INVISIBLE (8000 3325);
FORCEPROP 1 LAST PART_NUMBER CH747LM8825
J 0
(8025 3025);
DISPLAY 0.489362 (8025 3025);
PAINT SKYBLUE (8025 3025);
DISPLAY INVISIBLE (8025 3025);
FORCEADD VCC_CORE..1
(7950 3500);
FORCEPROP 3 LASTPIN (7950 3450) SIG_NAME PVDDIO_P0\g
J 0
(7960 3460);
DISPLAY 0.659574 (7960 3460);
PAINT MONO (7960 3460);
DISPLAY INVISIBLE (7960 3460);
FORCEPROP 1 LAST HDL_POWER PVDDIO_P0
J 1
(7950 3550);
DISPLAY 0.489362 (7950 3550);
PAINT GREEN (7950 3550);
FORCEPROP 2 LAST CDS_LIB pure_quanta_power
J 0
(7950 3500);
DISPLAY INVISIBLE (7950 3500);
FORCEPROP 1 LAST PATH I59
J 0
(8000 3525);
DISPLAY 0.872340 (8000 3525);
PAINT AQUA (8000 3525);
DISPLAY INVISIBLE (8000 3525);
FORCEADD OFFPAGE..5
(1300 1675);
FORCEPROP 2 LAST $XR2 200 
J 0
(1045 1711);
DISPLAY 0.638298 (1045 1711);
PAINT MONO (1045 1711);
FORCEPROP 2 LAST $XR1 206 
J 0
(1045 1639);
DISPLAY 0.638298 (1045 1639);
PAINT MONO (1045 1639);
FORCEPROP 2 LAST $XR0 205 
J 0
(1045 1675);
DISPLAY 0.638298 (1045 1675);
PAINT MONO (1045 1675);
FORCEPROP 2 LAST CDS_LIB standard
J 0
(1300 1675);
DISPLAY INVISIBLE (1300 1675);
FORCEPROP 1 LAST OFFPAGE TRUE
J 0
(1625 1550);
DISPLAY 0.872340 (1625 1550);
PAINT GREEN (1625 1550);
DISPLAY INVISIBLE (1625 1550);
FORCEPROP 1 LAST COMMENT_BODY TRUE
J 0
(1400 1600);
DISPLAY 0.872340 (1400 1600);
PAINT GREEN (1400 1600);
DISPLAY INVISIBLE (1400 1600);
FORCEPROP 2 LAST PATH I6
J 0
(1025 1750);
DISPLAY 0.680851 (1025 1750);
DISPLAY INVISIBLE (1025 1750);
FORCEADD Q_RES..2
(4325 4225);
FORCEPROP 1 LAST LOCATION PR221
J 0
(4370 4350);
DISPLAY 0.489362 (4370 4350);
PAINT SKYBLUE (4370 4350);
FORCEPROP 0 LAST $SEC 1
J 0
(4375 4400);
DISPLAY 0.680851 (4375 4400);
PAINT MONO (4375 4400);
DISPLAY INVISIBLE (4375 4400);
FORCEPROP 0 LAST CDS_SEC 1
J 0
(4375 4400);
DISPLAY 1.021277 (4375 4400);
DISPLAY INVISIBLE (4375 4400);
FORCEPROP 1 LASTPIN (4325 4325) $PN 1
J 0
(4330 4287);
DISPLAY 0.489362 (4330 4287);
PAINT MONO (4330 4287);
FORCEPROP 1 LASTPIN (4325 4125) $PN 2
J 0
(4330 4135);
DISPLAY 0.489362 (4330 4135);
PAINT MONO (4330 4135);
FORCEPROP 1 LAST PACK_TYPE 0402LF
J 0
(4365 4050);
DISPLAY 0.489362 (4365 4050);
PAINT SKYBLUE (4365 4050);
FORCEPROP 1 LAST VALUE 1.5
J 0
(4370 4300);
DISPLAY 0.489362 (4370 4300);
PAINT SKYBLUE (4370 4300);
FORCEPROP 1 LAST MATERIAL EMPTY
J 0
(4365 4150);
DISPLAY 0.489362 (4365 4150);
PAINT RED (4365 4150);
FORCEPROP 1 LAST WATTAGE 1/8W
J 0
(4365 4200);
DISPLAY 0.489362 (4365 4200);
PAINT SKYBLUE (4365 4200);
FORCEPROP 1 LAST TOLERANCE 1%
J 0
(4370 4250);
DISPLAY 0.489362 (4370 4250);
PAINT SKYBLUE (4370 4250);
FORCEPROP 2 LAST CDS_LIB pure_quanta
J 0
(4325 4225);
DISPLAY INVISIBLE (4325 4225);
FORCEPROP 1 LAST PATH I60
J 0
(4375 4400);
DISPLAY 0.978723 (4375 4400);
PAINT WHITE (4375 4400);
DISPLAY INVISIBLE (4375 4400);
FORCEPROP 1 LAST PART_NUMBER CS-1504FB00
J 0
(4365 4100);
DISPLAY 0.489362 (4365 4100);
PAINT SKYBLUE (4365 4100);
DISPLAY INVISIBLE (4365 4100);
FORCEADD Q_CAP..1
(4325 4775);
FORCEPROP 1 LAST LOCATION PC158
J 0
(4375 4875);
DISPLAY 0.489362 (4375 4875);
PAINT SKYBLUE (4375 4875);
FORCEPROP 0 LAST $SEC 1
J 0
(4375 4925);
DISPLAY 0.680851 (4375 4925);
PAINT MONO (4375 4925);
DISPLAY INVISIBLE (4375 4925);
FORCEPROP 0 LAST CDS_SEC 1
J 0
(4375 4925);
DISPLAY 1.021277 (4375 4925);
DISPLAY INVISIBLE (4375 4925);
FORCEPROP 1 LASTPIN (4325 4875) $PN 1
J 0
(4335 4855);
DISPLAY 0.489362 (4335 4855);
PAINT MONO (4335 4855);
FORCEPROP 1 LASTPIN (4325 4675) $PN 2
J 0
(4335 4655);
DISPLAY 0.489362 (4335 4655);
PAINT MONO (4335 4655);
FORCEPROP 1 LAST PACK_TYPE C0402
J 0
(4375 4575);
DISPLAY 0.489362 (4375 4575);
PAINT SKYBLUE (4375 4575);
FORCEPROP 1 LAST TOLERANCE 10%
J 0
(4375 4725);
DISPLAY 0.489362 (4375 4725);
PAINT SKYBLUE (4375 4725);
FORCEPROP 1 LAST MATERIAL EMPTY
J 0
(4375 4675);
DISPLAY 0.489362 (4375 4675);
PAINT RED (4375 4675);
FORCEPROP 1 LAST VOLTAGE 50V
J 0
(4375 4775);
DISPLAY 0.489362 (4375 4775);
PAINT SKYBLUE (4375 4775);
FORCEPROP 1 LAST VALUE 560PF
J 0
(4375 4825);
DISPLAY 0.489362 (4375 4825);
PAINT SKYBLUE (4375 4825);
FORCEPROP 2 LAST CDS_LIB pure_quanta
J 0
(4325 4775);
DISPLAY INVISIBLE (4325 4775);
FORCEPROP 1 LAST PATH I61
J 0
(4375 4925);
DISPLAY 0.978723 (4375 4925);
PAINT WHITE (4375 4925);
DISPLAY INVISIBLE (4375 4925);
FORCEPROP 1 LAST PART_NUMBER CH1566K1B09
J 0
(4375 4625);
DISPLAY 0.489362 (4375 4625);
PAINT SKYBLUE (4375 4625);
DISPLAY INVISIBLE (4375 4625);
FORCEADD OFFPAGE..6
(5025 4725);
FORCEPROP 2 LAST $XR0 205 
J 0
(4715 4725);
DISPLAY 0.638298 (4715 4725);
PAINT MONO (4715 4725);
FORCEPROP 2 LAST CDS_LIB standard
J 0
(5025 4725);
DISPLAY INVISIBLE (5025 4725);
FORCEPROP 1 LAST OFFPAGE TRUE
J 0
(5350 4600);
DISPLAY 0.872340 (5350 4600);
PAINT GREEN (5350 4600);
DISPLAY INVISIBLE (5350 4600);
FORCEPROP 1 LAST COMMENT_BODY TRUE
J 0
(5125 4650);
DISPLAY 0.872340 (5125 4650);
PAINT GREEN (5125 4650);
DISPLAY INVISIBLE (5125 4650);
FORCEPROP 2 LAST PATH I62
J 0
(4725 4775);
DISPLAY 0.680851 (4725 4775);
DISPLAY INVISIBLE (4725 4775);
FORCEADD Q_CAP..1
(4850 5200);
FORCEPROP 1 LAST LOCATION PC155
J 0
(4900 5300);
DISPLAY 0.489362 (4900 5300);
PAINT SKYBLUE (4900 5300);
FORCEPROP 0 LAST $SEC 1
J 0
(4900 5350);
DISPLAY 0.680851 (4900 5350);
PAINT MONO (4900 5350);
DISPLAY INVISIBLE (4900 5350);
FORCEPROP 0 LAST CDS_SEC 1
J 2
(4900 5325);
DISPLAY 1.021277 (4900 5325);
DISPLAY INVISIBLE (4900 5325);
FORCEPROP 1 LASTPIN (4850 5300) $PN 1
J 0
(4860 5280);
DISPLAY 0.489362 (4860 5280);
PAINT MONO (4860 5280);
FORCEPROP 1 LASTPIN (4850 5100) $PN 2
J 0
(4860 5080);
DISPLAY 0.489362 (4860 5080);
PAINT MONO (4860 5080);
FORCEPROP 1 LAST VALUE 0.22UF
J 0
(4900 5250);
DISPLAY 0.489362 (4900 5250);
PAINT SKYBLUE (4900 5250);
FORCEPROP 1 LAST PACK_TYPE 0402
J 0
(4900 5000);
DISPLAY 0.489362 (4900 5000);
PAINT SKYBLUE (4900 5000);
FORCEPROP 1 LAST VOLTAGE 16V
J 0
(4900 5200);
DISPLAY 0.489362 (4900 5200);
PAINT SKYBLUE (4900 5200);
FORCEPROP 1 LAST MATERIAL X7R
J 0
(4900 5100);
DISPLAY 0.489362 (4900 5100);
PAINT SKYBLUE (4900 5100);
FORCEPROP 1 LAST TOLERANCE 10%
J 0
(4900 5150);
DISPLAY 0.489362 (4900 5150);
PAINT SKYBLUE (4900 5150);
FORCEPROP 2 LAST CDS_LIB pure_quanta
J 2
(4850 5200);
DISPLAY INVISIBLE (4850 5200);
FORCEPROP 1 LAST PATH I63
J 0
(4900 5350);
DISPLAY 0.978723 (4900 5350);
PAINT WHITE (4900 5350);
DISPLAY INVISIBLE (4900 5350);
FORCEPROP 1 LAST PART_NUMBER CH4223K1B00
J 0
(4900 5050);
DISPLAY 0.489362 (4900 5050);
PAINT SKYBLUE (4900 5050);
DISPLAY INVISIBLE (4900 5050);
FORCEADD Q_INDUCTOR4P_14..1
(6050 4850);
FORCEPROP 1 LAST LOCATION PL17
J 0
(5775 5025);
DISPLAY 0.489362 (5775 5025);
PAINT SKYBLUE (5775 5025);
FORCEPROP 0 LAST $SEC 1
J 0
(6100 5050);
DISPLAY 0.680851 (6100 5050);
PAINT MONO (6100 5050);
DISPLAY INVISIBLE (6100 5050);
FORCEPROP 0 LAST CDS_SEC 1
J 0
(6100 5050);
DISPLAY 1.021277 (6100 5050);
DISPLAY INVISIBLE (6100 5050);
FORCEPROP 0 LASTPIN (5650 4975) $PN 1
J 2
(5640 4985);
DISPLAY 0.489362 (5640 4985);
PAINT MONO (5640 4985);
FORCEPROP 0 LASTPIN (5650 4725) $PN 2
J 2
(5640 4735);
DISPLAY 0.489362 (5640 4735);
PAINT MONO (5640 4735);
FORCEPROP 0 LASTPIN (6450 4725) $PN 3
J 0
(6460 4735);
DISPLAY 0.489362 (6460 4735);
PAINT MONO (6460 4735);
FORCEPROP 0 LASTPIN (6450 4975) $PN 4
J 0
(6460 4985);
DISPLAY 0.489362 (6460 4985);
PAINT MONO (6460 4985);
FORCEPROP 2 LAST VALUE 150NH
J 0
(5950 5025);
DISPLAY 0.489362 (5950 5025);
PAINT SKYBLUE (5950 5025);
FORCEPROP 1 LAST MATERIAL IND
J 0
(5850 5025);
DISPLAY 0.489362 (5850 5025);
PAINT SKYBLUE (5850 5025);
FORCEPROP 2 LAST PART_TYPE SMLF
J 0
(5975 4600);
DISPLAY 1.021277 (5975 4600);
FORCEPROP 2 LAST CDS_LIB pure_quanta
J 0
(6050 4850);
DISPLAY INVISIBLE (6050 4850);
FORCEPROP 1 LAST NEEDS_NO_SIZE TRUE
J 0
(6050 4850);
DISPLAY 0.468085 (6050 4850);
PAINT GREEN (6050 4850);
DISPLAY INVISIBLE (6050 4850);
FORCEPROP 1 LAST PATH I64
J 0
(6250 5005);
DISPLAY 0.723404 (6250 5005);
PAINT GREEN (6250 5005);
DISPLAY INVISIBLE (6250 5005);
FORCEPROP 1 LAST PART_NUMBER CV+15^0TZ04
J 0
(6100 5025);
DISPLAY 0.489362 (6100 5025);
PAINT SKYBLUE (6100 5025);
DISPLAY INVISIBLE (6100 5025);
FORCEADD UNIVERSAL_GND..1
(5450 5525);
FORCEPROP 3 LASTPIN (5450 5575) SIG_NAME GND\g
J 0
(5460 5585);
DISPLAY 0.659574 (5460 5585);
PAINT MONO (5460 5585);
DISPLAY INVISIBLE (5460 5585);
FORCEPROP 2 LAST CDS_LIB pure_quanta_power
J 0
(5450 5525);
PAINT MONO (5450 5525);
DISPLAY INVISIBLE (5450 5525);
FORCEPROP 1 LAST HDL_POWER GND
J 1
(5475 5450);
DISPLAY 0.872340 (5475 5450);
PAINT GREEN (5475 5450);
DISPLAY INVISIBLE (5475 5450);
FORCEPROP 1 LAST PATH I65
J 0
(5525 5525);
DISPLAY 0.872340 (5525 5525);
PAINT AQUA (5525 5525);
DISPLAY INVISIBLE (5525 5525);
FORCEADD Q_CAP..1
(5075 5900);
FORCEPROP 1 LAST LOCATION PC158_1
J 0
(5125 6000);
DISPLAY 0.489362 (5125 6000);
PAINT SKYBLUE (5125 6000);
FORCEPROP 0 LAST $SEC 1
J 0
(5125 6050);
DISPLAY 0.680851 (5125 6050);
PAINT MONO (5125 6050);
DISPLAY INVISIBLE (5125 6050);
FORCEPROP 0 LAST CDS_SEC 1
J 0
(5125 6050);
DISPLAY 1.021277 (5125 6050);
DISPLAY INVISIBLE (5125 6050);
FORCEPROP 1 LASTPIN (5075 6000) $PN 1
J 0
(5085 5980);
DISPLAY 0.489362 (5085 5980);
PAINT MONO (5085 5980);
FORCEPROP 1 LASTPIN (5075 5800) $PN 2
J 0
(5085 5780);
DISPLAY 0.489362 (5085 5780);
PAINT MONO (5085 5780);
FORCEPROP 1 LAST PACK_TYPE C0805
J 0
(5125 5700);
DISPLAY 0.489362 (5125 5700);
PAINT SKYBLUE (5125 5700);
FORCEPROP 1 LAST VALUE 22UF
J 0
(5125 5950);
DISPLAY 0.489362 (5125 5950);
PAINT SKYBLUE (5125 5950);
FORCEPROP 1 LAST MATERIAL X6S
J 0
(5125 5800);
DISPLAY 0.489362 (5125 5800);
PAINT SKYBLUE (5125 5800);
FORCEPROP 1 LAST TOLERANCE 20%
J 0
(5125 5850);
DISPLAY 0.489362 (5125 5850);
PAINT SKYBLUE (5125 5850);
FORCEPROP 1 LAST VOLTAGE 16V
J 0
(5125 5900);
DISPLAY 0.489362 (5125 5900);
PAINT SKYBLUE (5125 5900);
FORCEPROP 2 LAST CDS_LIB pure_quanta
J 0
(5075 5900);
DISPLAY INVISIBLE (5075 5900);
FORCEPROP 1 LAST PATH I66
J 0
(5125 6050);
DISPLAY 0.978723 (5125 6050);
PAINT WHITE (5125 6050);
DISPLAY INVISIBLE (5125 6050);
FORCEPROP 1 LAST PART_NUMBER CH6223MEA01
J 0
(5125 5750);
DISPLAY 0.489362 (5125 5750);
PAINT SKYBLUE (5125 5750);
DISPLAY INVISIBLE (5125 5750);
FORCEADD Q_CAPP..1
(5725 5900);
FORCEPROP 1 LAST LOCATION PC164
J 0
(5775 6025);
DISPLAY 0.489362 (5775 6025);
PAINT SKYBLUE (5775 6025);
FORCEPROP 0 LAST $SEC 1
J 0
(5775 6025);
DISPLAY 0.680851 (5775 6025);
PAINT MONO (5775 6025);
DISPLAY INVISIBLE (5775 6025);
FORCEPROP 0 LAST CDS_SEC 1
J 0
(5775 6025);
DISPLAY 1.021277 (5775 6025);
DISPLAY INVISIBLE (5775 6025);
FORCEPROP 1 LASTPIN (5725 6000) $PN 1
J 0
(5735 5985);
DISPLAY 0.489362 (5735 5985);
PAINT MONO (5735 5985);
FORCEPROP 1 LASTPIN (5725 5800) $PN 2
J 0
(5735 5785);
DISPLAY 0.489362 (5735 5785);
PAINT MONO (5735 5785);
FORCEPROP 1 LAST TOLERANCE 20%
J 0
(5775 5925);
DISPLAY 0.489362 (5775 5925);
PAINT SKYBLUE (5775 5925);
FORCEPROP 1 LAST PACK_TYPE THLF
J 0
(5775 5775);
DISPLAY 0.489362 (5775 5775);
PAINT SKYBLUE (5775 5775);
FORCEPROP 1 LAST MATERIAL OSCON
J 0
(5775 5825);
DISPLAY 0.489362 (5775 5825);
PAINT SKYBLUE (5775 5825);
FORCEPROP 1 LAST VOLTAGE 16V
J 0
(5775 5875);
DISPLAY 0.489362 (5775 5875);
PAINT SKYBLUE (5775 5875);
FORCEPROP 1 LAST VALUE 270UF
J 0
(5775 5975);
DISPLAY 0.489362 (5775 5975);
PAINT SKYBLUE (5775 5975);
FORCEPROP 2 LAST CDS_LIB pure_quanta
J 0
(5725 5900);
DISPLAY INVISIBLE (5725 5900);
FORCEPROP 1 LAST PATH I67
J 0
(5775 6050);
DISPLAY 0.978723 (5775 6050);
DISPLAY INVISIBLE (5775 6050);
FORCEPROP 1 LAST PART_NUMBER CC72703MD38
J 0
(5775 5725);
DISPLAY 0.489362 (5775 5725);
PAINT SKYBLUE (5775 5725);
DISPLAY INVISIBLE (5775 5725);
FORCEADD VCC_CORE..1
(5450 6250);
FORCEPROP 3 LASTPIN (5450 6200) SIG_NAME SW_P12V_AUX_PVDDIO_P0_FLT\g
J 0
(5460 6210);
DISPLAY 0.659574 (5460 6210);
PAINT MONO (5460 6210);
DISPLAY INVISIBLE (5460 6210);
FORCEPROP 1 LAST HDL_POWER SW_P12V_AUX_PVDDIO_P0_FLT
J 1
(5450 6300);
DISPLAY 0.489362 (5450 6300);
PAINT GREEN (5450 6300);
FORCEPROP 2 LAST CDS_LIB pure_quanta_power
J 0
(5450 6250);
DISPLAY INVISIBLE (5450 6250);
FORCEPROP 1 LAST PATH I68
J 0
(5500 6275);
DISPLAY 0.872340 (5500 6275);
PAINT AQUA (5500 6275);
DISPLAY INVISIBLE (5500 6275);
FORCEADD Q_INDUCTOR..1
(6075 6150);
FORCEPROP 1 LAST LOCATION PL19
J 0
(6200 6175);
DISPLAY 0.489362 (6200 6175);
PAINT SKYBLUE (6200 6175);
FORCEPROP 2 LAST $SEC 1
J 0
(6150 6250);
DISPLAY 0.680851 (6150 6250);
PAINT MONO (6150 6250);
DISPLAY INVISIBLE (6150 6250);
FORCEPROP 2 LAST CDS_SEC 1
J 0
(6150 6250);
DISPLAY 1.021277 (6150 6250);
DISPLAY INVISIBLE (6150 6250);
FORCEPROP 2 LASTPIN (5975 6125) $PN 1
J 2
(5965 6135);
DISPLAY 0.489362 (5965 6135);
FORCEPROP 2 LASTPIN (6175 6125) $PN 2
J 0
(6185 6135);
DISPLAY 0.489362 (6185 6135);
FORCEPROP 1 LAST MATERIAL IND
J 0
(5975 6275);
DISPLAY 0.489362 (5975 6275);
PAINT SKYBLUE (5975 6275);
FORCEPROP 2 LAST PACK_TYPE SMLF
J 0
(5975 6325);
DISPLAY 0.489362 (5975 6325);
PAINT SKYBLUE (5975 6325);
FORCEPROP 2 LAST VALUE 50NH/86A
J 0
(5975 6375);
DISPLAY 0.489362 (5975 6375);
PAINT SKYBLUE (5975 6375);
FORCEPROP 2 LAST CDS_LIB pure_quanta
J 0
(6075 6150);
PAINT MONO (6075 6150);
DISPLAY INVISIBLE (6075 6150);
FORCEPROP 1 LAST NEEDS_NO_SIZE TRUE
J 0
(6075 6150);
DISPLAY 0.468085 (6075 6150);
PAINT GREEN (6075 6150);
DISPLAY INVISIBLE (6075 6150);
FORCEPROP 1 LAST PATH I69
J 0
(6150 6205);
DISPLAY 0.723404 (6150 6205);
PAINT GREEN (6150 6205);
DISPLAY INVISIBLE (6150 6205);
FORCEPROP 1 LAST PART_NUMBER CVA50^0MZ09
J 0
(5975 6225);
DISPLAY 0.489362 (5975 6225);
PAINT SKYBLUE (5975 6225);
DISPLAY INVISIBLE (5975 6225);
FORCEADD OFFPAGE..1
(1300 2075);
FORCEPROP 2 LAST $XR1 201 
J 0
(898 2075);
DISPLAY 0.638298 (898 2075);
PAINT MONO (898 2075);
FORCEPROP 2 LAST $XR0 200 
J 0
(1018 2075);
DISPLAY 0.638298 (1018 2075);
PAINT MONO (1018 2075);
FORCEPROP 2 LAST $XR3 203 
J 0
(658 2075);
DISPLAY 0.638298 (658 2075);
PAINT MONO (658 2075);
FORCEPROP 2 LAST $XR2 202 
J 0
(778 2075);
DISPLAY 0.638298 (778 2075);
PAINT MONO (778 2075);
FORCEPROP 2 LAST $XR4 205 
J 0
(538 2075);
DISPLAY 0.638298 (538 2075);
PAINT MONO (538 2075);
FORCEPROP 2 LAST $XR5 206 
J 0
(418 2075);
DISPLAY 0.638298 (418 2075);
PAINT MONO (418 2075);
FORCEPROP 2 LAST CDS_LIB standard
J 0
(1300 2075);
DISPLAY INVISIBLE (1300 2075);
FORCEPROP 1 LAST OFFPAGE TRUE
J 0
(1625 1950);
DISPLAY 0.872340 (1625 1950);
PAINT GREEN (1625 1950);
DISPLAY INVISIBLE (1625 1950);
FORCEPROP 1 LAST COMMENT_BODY TRUE
J 0
(1425 1975);
DISPLAY 0.872340 (1425 1975);
PAINT GREEN (1425 1975);
DISPLAY INVISIBLE (1425 1975);
FORCEPROP 2 LAST PATH I7
J 0
(1050 2125);
DISPLAY 0.680851 (1050 2125);
DISPLAY INVISIBLE (1050 2125);
FORCEADD UNIVERSAL_GND..1
(6925 4600);
FORCEPROP 3 LASTPIN (6925 4650) SIG_NAME GND\g
J 0
(6935 4660);
DISPLAY 0.659574 (6935 4660);
PAINT MONO (6935 4660);
DISPLAY INVISIBLE (6935 4660);
FORCEPROP 2 LAST CDS_LIB pure_quanta_power
J 0
(6925 4600);
DISPLAY INVISIBLE (6925 4600);
FORCEPROP 1 LAST HDL_POWER GND
J 1
(6950 4525);
DISPLAY 0.872340 (6950 4525);
PAINT GREEN (6950 4525);
DISPLAY INVISIBLE (6950 4525);
FORCEPROP 1 LAST PATH I70
J 0
(7000 4600);
DISPLAY 0.872340 (7000 4600);
PAINT AQUA (7000 4600);
DISPLAY INVISIBLE (7000 4600);
FORCEADD UNIVERSAL_GND..1
(6600 5600);
FORCEPROP 3 LASTPIN (6600 5650) SIG_NAME GND\g
J 0
(6610 5660);
DISPLAY 0.659574 (6610 5660);
PAINT MONO (6610 5660);
DISPLAY INVISIBLE (6610 5660);
FORCEPROP 2 LAST CDS_LIB pure_quanta_power
J 0
(6600 5600);
DISPLAY INVISIBLE (6600 5600);
FORCEPROP 1 LAST HDL_POWER GND
J 1
(6625 5525);
DISPLAY 0.872340 (6625 5525);
PAINT GREEN (6625 5525);
DISPLAY INVISIBLE (6625 5525);
FORCEPROP 1 LAST PATH I71
J 0
(6675 5600);
DISPLAY 0.872340 (6675 5600);
PAINT AQUA (6675 5600);
DISPLAY INVISIBLE (6675 5600);
FORCEADD Q_CAP..1
(6600 5925);
FORCEPROP 1 LAST LOCATION PC148
J 0
(6675 6075);
DISPLAY 0.489362 (6675 6075);
PAINT SKYBLUE (6675 6075);
FORCEPROP 0 LAST $SEC 1
J 0
(6675 6100);
DISPLAY 0.680851 (6675 6100);
PAINT MONO (6675 6100);
DISPLAY INVISIBLE (6675 6100);
FORCEPROP 0 LAST CDS_SEC 1
J 0
(6675 6100);
DISPLAY 0.680851 (6675 6100);
DISPLAY INVISIBLE (6675 6100);
FORCEPROP 1 LASTPIN (6600 6025) $PN 1
J 0
(6610 6005);
DISPLAY 0.787234 (6610 6005);
PAINT MONO (6610 6005);
FORCEPROP 1 LASTPIN (6600 5825) $PN 2
J 0
(6610 5805);
DISPLAY 0.787234 (6610 5805);
PAINT MONO (6610 5805);
FORCEPROP 1 LAST TOLERANCE 10%
J 0
(6675 5925);
DISPLAY 0.489362 (6675 5925);
PAINT SKYBLUE (6675 5925);
FORCEPROP 1 LAST PACK_TYPE 0402
J 0
(6675 5775);
DISPLAY 0.489362 (6675 5775);
PAINT SKYBLUE (6675 5775);
FORCEPROP 1 LAST VOLTAGE 25V
J 0
(6675 5975);
DISPLAY 0.489362 (6675 5975);
PAINT SKYBLUE (6675 5975);
FORCEPROP 1 LAST MATERIAL X7R
J 0
(6675 5875);
DISPLAY 0.489362 (6675 5875);
PAINT SKYBLUE (6675 5875);
FORCEPROP 1 LAST VALUE 0.1UF
J 0
(6675 6025);
DISPLAY 0.489362 (6675 6025);
PAINT SKYBLUE (6675 6025);
FORCEPROP 2 LAST CDS_LIB pure_quanta
J 0
(6600 5925);
DISPLAY INVISIBLE (6600 5925);
FORCEPROP 1 LAST PATH I72
J 0
(6650 6075);
DISPLAY 0.978723 (6650 6075);
PAINT WHITE (6650 6075);
DISPLAY INVISIBLE (6650 6075);
FORCEPROP 1 LAST PART_NUMBER CH4104K1B00
J 0
(6675 5825);
DISPLAY 0.489362 (6675 5825);
PAINT SKYBLUE (6675 5825);
DISPLAY INVISIBLE (6675 5825);
FORCEADD Q_CAP..1
(7200 4775);
FORCEPROP 1 LAST LOCATION PC107
J 0
(7250 4900);
DISPLAY 0.489362 (7250 4900);
PAINT SKYBLUE (7250 4900);
FORCEPROP 0 LAST $SEC 1
J 0
(7250 4950);
DISPLAY 0.680851 (7250 4950);
PAINT MONO (7250 4950);
DISPLAY INVISIBLE (7250 4950);
FORCEPROP 0 LAST CDS_SEC 1
J 0
(7250 4950);
DISPLAY 1.021277 (7250 4950);
DISPLAY INVISIBLE (7250 4950);
FORCEPROP 1 LASTPIN (7200 4875) $PN 1
J 0
(7210 4855);
DISPLAY 0.489362 (7210 4855);
PAINT MONO (7210 4855);
FORCEPROP 1 LASTPIN (7200 4675) $PN 2
J 0
(7210 4655);
DISPLAY 0.489362 (7210 4655);
PAINT MONO (7210 4655);
FORCEPROP 1 LAST VALUE 0.1UF
J 0
(7250 4850);
DISPLAY 0.489362 (7250 4850);
PAINT SKYBLUE (7250 4850);
FORCEPROP 1 LAST PACK_TYPE 0402
J 0
(7250 4650);
DISPLAY 0.489362 (7250 4650);
PAINT SKYBLUE (7250 4650);
FORCEPROP 1 LAST VOLTAGE 25V
J 0
(7250 4800);
DISPLAY 0.489362 (7250 4800);
PAINT SKYBLUE (7250 4800);
FORCEPROP 1 LAST TOLERANCE 10%
J 0
(7250 4750);
DISPLAY 0.489362 (7250 4750);
PAINT SKYBLUE (7250 4750);
FORCEPROP 1 LAST MATERIAL X7R
J 0
(7250 4700);
DISPLAY 0.489362 (7250 4700);
PAINT SKYBLUE (7250 4700);
FORCEPROP 2 LAST CDS_LIB pure_quanta
J 0
(7200 4775);
DISPLAY INVISIBLE (7200 4775);
FORCEPROP 1 LAST PATH I73
J 0
(7250 4925);
DISPLAY 0.978723 (7250 4925);
PAINT WHITE (7250 4925);
DISPLAY INVISIBLE (7250 4925);
FORCEPROP 1 LAST PART_NUMBER CH4104K1B00
J 0
(7250 4600);
DISPLAY 0.489362 (7250 4600);
PAINT SKYBLUE (7250 4600);
DISPLAY INVISIBLE (7250 4600);
FORCEADD Q_CAP..1
(7700 4775);
FORCEPROP 1 LAST LOCATION PC166_1
J 0
(7750 4900);
DISPLAY 0.489362 (7750 4900);
PAINT SKYBLUE (7750 4900);
FORCEPROP 0 LAST $SEC 1
J 0
(7750 4950);
DISPLAY 0.680851 (7750 4950);
PAINT MONO (7750 4950);
DISPLAY INVISIBLE (7750 4950);
FORCEPROP 0 LAST CDS_SEC 1
J 0
(7750 4950);
DISPLAY 1.021277 (7750 4950);
DISPLAY INVISIBLE (7750 4950);
FORCEPROP 1 LASTPIN (7700 4875) $PN 1
J 0
(7710 4855);
DISPLAY 0.489362 (7710 4855);
PAINT MONO (7710 4855);
FORCEPROP 1 LASTPIN (7700 4675) $PN 2
J 0
(7710 4655);
DISPLAY 0.489362 (7710 4655);
PAINT MONO (7710 4655);
FORCEPROP 1 LAST PACK_TYPE C0805
J 0
(7750 4650);
DISPLAY 0.489362 (7750 4650);
PAINT SKYBLUE (7750 4650);
FORCEPROP 1 LAST MATERIAL X6S
J 0
(7750 4700);
DISPLAY 0.489362 (7750 4700);
PAINT SKYBLUE (7750 4700);
FORCEPROP 1 LAST TOLERANCE 20%
J 0
(7750 4750);
DISPLAY 0.489362 (7750 4750);
PAINT SKYBLUE (7750 4750);
FORCEPROP 1 LAST VALUE 22UF
J 0
(7750 4850);
DISPLAY 0.489362 (7750 4850);
PAINT SKYBLUE (7750 4850);
FORCEPROP 1 LAST VOLTAGE 4V
J 0
(7750 4800);
DISPLAY 0.489362 (7750 4800);
PAINT SKYBLUE (7750 4800);
FORCEPROP 2 LAST CDS_LIB pure_quanta
J 0
(7700 4775);
DISPLAY INVISIBLE (7700 4775);
FORCEPROP 1 LAST PATH I74
J 0
(7750 4925);
DISPLAY 0.978723 (7750 4925);
PAINT WHITE (7750 4925);
DISPLAY INVISIBLE (7750 4925);
FORCEPROP 1 LAST PART_NUMBER CH622KMEA03
J 0
(7750 4600);
DISPLAY 0.489362 (7750 4600);
PAINT SKYBLUE (7750 4600);
DISPLAY INVISIBLE (7750 4600);
FORCEADD Q_CAP..1
(8125 4775);
FORCEPROP 1 LAST LOCATION PC169_1
J 0
(8175 4900);
DISPLAY 0.489362 (8175 4900);
PAINT SKYBLUE (8175 4900);
FORCEPROP 0 LAST $SEC 1
J 0
(8175 4950);
DISPLAY 0.680851 (8175 4950);
PAINT MONO (8175 4950);
DISPLAY INVISIBLE (8175 4950);
FORCEPROP 0 LAST CDS_SEC 1
J 0
(8175 4950);
DISPLAY 1.021277 (8175 4950);
DISPLAY INVISIBLE (8175 4950);
FORCEPROP 1 LASTPIN (8125 4875) $PN 1
J 0
(8135 4855);
DISPLAY 0.489362 (8135 4855);
PAINT MONO (8135 4855);
FORCEPROP 1 LASTPIN (8125 4675) $PN 2
J 0
(8135 4655);
DISPLAY 0.489362 (8135 4655);
PAINT MONO (8135 4655);
FORCEPROP 1 LAST PACK_TYPE C0805
J 0
(8175 4650);
DISPLAY 0.489362 (8175 4650);
PAINT SKYBLUE (8175 4650);
FORCEPROP 1 LAST MATERIAL X6S
J 0
(8175 4700);
DISPLAY 0.489362 (8175 4700);
PAINT SKYBLUE (8175 4700);
FORCEPROP 1 LAST TOLERANCE 20%
J 0
(8175 4750);
DISPLAY 0.489362 (8175 4750);
PAINT SKYBLUE (8175 4750);
FORCEPROP 1 LAST VALUE 22UF
J 0
(8175 4850);
DISPLAY 0.489362 (8175 4850);
PAINT SKYBLUE (8175 4850);
FORCEPROP 1 LAST VOLTAGE 4V
J 0
(8175 4800);
DISPLAY 0.489362 (8175 4800);
PAINT SKYBLUE (8175 4800);
FORCEPROP 2 LAST CDS_LIB pure_quanta
J 0
(8125 4775);
DISPLAY INVISIBLE (8125 4775);
FORCEPROP 1 LAST PATH I75
J 0
(8175 4925);
DISPLAY 0.978723 (8175 4925);
PAINT WHITE (8175 4925);
DISPLAY INVISIBLE (8175 4925);
FORCEPROP 1 LAST PART_NUMBER CH622KMEA03
J 0
(8150 4600);
DISPLAY 0.489362 (8150 4600);
PAINT SKYBLUE (8150 4600);
DISPLAY INVISIBLE (8150 4600);
FORCEADD VCC_CORE..1
(6600 6250);
FORCEPROP 3 LASTPIN (6600 6200) SIG_NAME P12V_AUX\g
J 0
(6610 6210);
DISPLAY 0.659574 (6610 6210);
PAINT MONO (6610 6210);
DISPLAY INVISIBLE (6610 6210);
FORCEPROP 1 LAST HDL_POWER P12V_AUX
J 1
(6600 6300);
DISPLAY 0.489362 (6600 6300);
PAINT GREEN (6600 6300);
FORCEPROP 2 LAST CDS_LIB pure_quanta_power
J 0
(6600 6250);
DISPLAY INVISIBLE (6600 6250);
FORCEPROP 1 LAST PATH I76
J 0
(6650 6275);
DISPLAY 0.872340 (6650 6275);
PAINT AQUA (6650 6275);
DISPLAY INVISIBLE (6650 6275);
FORCEADD UNIVERSAL_GND..1
(8425 4425);
FORCEPROP 3 LASTPIN (8425 4475) SIG_NAME GND\g
J 0
(8435 4485);
DISPLAY 0.659574 (8435 4485);
PAINT MONO (8435 4485);
DISPLAY INVISIBLE (8435 4485);
FORCEPROP 2 LAST CDS_LIB pure_quanta_power
J 0
(8425 4425);
PAINT MONO (8425 4425);
DISPLAY INVISIBLE (8425 4425);
FORCEPROP 1 LAST HDL_POWER GND
J 1
(8450 4350);
DISPLAY 0.872340 (8450 4350);
PAINT GREEN (8450 4350);
DISPLAY INVISIBLE (8450 4350);
FORCEPROP 1 LAST PATH I77
J 0
(8500 4425);
DISPLAY 0.872340 (8500 4425);
PAINT AQUA (8500 4425);
DISPLAY INVISIBLE (8500 4425);
FORCEADD Q_RES..2
(8425 4775);
FORCEPROP 1 LAST LOCATION PR410
J 0
(8470 4900);
DISPLAY 0.489362 (8470 4900);
PAINT SKYBLUE (8470 4900);
FORCEPROP 0 LAST $SEC 1
J 0
(8475 4925);
DISPLAY 0.680851 (8475 4925);
PAINT MONO (8475 4925);
DISPLAY INVISIBLE (8475 4925);
FORCEPROP 0 LAST CDS_SEC 1
J 0
(8475 4925);
DISPLAY 1.021277 (8475 4925);
DISPLAY INVISIBLE (8475 4925);
FORCEPROP 1 LASTPIN (8425 4875) $PN 1
J 0
(8430 4837);
DISPLAY 0.787234 (8430 4837);
PAINT MONO (8430 4837);
DISPLAY INVISIBLE (8430 4837);
FORCEPROP 1 LASTPIN (8425 4675) $PN 2
J 0
(8430 4685);
DISPLAY 0.787234 (8430 4685);
PAINT MONO (8430 4685);
DISPLAY INVISIBLE (8430 4685);
FORCEPROP 1 LAST WATTAGE 1/16W
J 0
(8465 4750);
DISPLAY 0.489362 (8465 4750);
PAINT SKYBLUE (8465 4750);
FORCEPROP 1 LAST MATERIAL CHIP
J 0
(8465 4700);
DISPLAY 0.489362 (8465 4700);
PAINT SKYBLUE (8465 4700);
FORCEPROP 1 LAST TOLERANCE 1%
J 0
(8470 4800);
DISPLAY 0.489362 (8470 4800);
PAINT SKYBLUE (8470 4800);
FORCEPROP 1 LAST VALUE 1K
J 0
(8470 4850);
DISPLAY 0.489362 (8470 4850);
PAINT SKYBLUE (8470 4850);
FORCEPROP 1 LAST PACK_TYPE 0402LF
J 0
(8465 4600);
DISPLAY 0.489362 (8465 4600);
PAINT SKYBLUE (8465 4600);
FORCEPROP 2 LAST CDS_LIB pure_quanta
J 0
(8425 4775);
DISPLAY INVISIBLE (8425 4775);
FORCEPROP 1 LAST PATH I78
J 0
(8475 4950);
DISPLAY 0.978723 (8475 4950);
PAINT WHITE (8475 4950);
DISPLAY INVISIBLE (8475 4950);
FORCEPROP 1 LAST PART_NUMBER CS21002FB06
J 0
(8465 4650);
DISPLAY 0.489362 (8465 4650);
PAINT SKYBLUE (8465 4650);
DISPLAY INVISIBLE (8465 4650);
FORCEADD VCC_CORE..1
(8425 5100);
FORCEPROP 3 LASTPIN (8425 5050) SIG_NAME PVDDIO_P0\g
J 0
(8435 5060);
DISPLAY 0.659574 (8435 5060);
PAINT MONO (8435 5060);
DISPLAY INVISIBLE (8435 5060);
FORCEPROP 1 LAST HDL_POWER PVDDIO_P0
J 1
(8425 5150);
DISPLAY 0.489362 (8425 5150);
PAINT GREEN (8425 5150);
FORCEPROP 2 LAST CDS_LIB pure_quanta_power
J 0
(8425 5100);
DISPLAY INVISIBLE (8425 5100);
FORCEPROP 1 LAST PATH I79
J 0
(8475 5125);
DISPLAY 0.872340 (8475 5125);
PAINT AQUA (8475 5125);
DISPLAY INVISIBLE (8475 5125);
FORCEADD OFFPAGE..5
(1300 2175);
FORCEPROP 2 LAST $XR0 200 
J 0
(1045 2175);
DISPLAY 0.638298 (1045 2175);
PAINT MONO (1045 2175);
FORCEPROP 2 LAST CDS_LIB standard
J 0
(1300 2175);
DISPLAY INVISIBLE (1300 2175);
FORCEPROP 1 LAST OFFPAGE TRUE
J 0
(1625 2050);
DISPLAY 0.872340 (1625 2050);
PAINT GREEN (1625 2050);
DISPLAY INVISIBLE (1625 2050);
FORCEPROP 1 LAST COMMENT_BODY TRUE
J 0
(1400 2100);
DISPLAY 0.872340 (1400 2100);
PAINT GREEN (1400 2100);
DISPLAY INVISIBLE (1400 2100);
FORCEPROP 2 LAST PATH I8
J 0
(1025 2225);
DISPLAY 0.680851 (1025 2225);
DISPLAY INVISIBLE (1025 2225);
FORCEADD Q_CAP..1
(4750 5875);
FORCEPROP 1 LAST LOCATION PC154_1
J 0
(4800 6025);
DISPLAY 0.489362 (4800 6025);
PAINT SKYBLUE (4800 6025);
FORCEPROP 0 LAST $SEC 1
J 0
(4800 6075);
DISPLAY 0.680851 (4800 6075);
PAINT MONO (4800 6075);
DISPLAY INVISIBLE (4800 6075);
FORCEPROP 0 LAST CDS_SEC 1
J 0
(4800 6075);
DISPLAY 1.021277 (4800 6075);
DISPLAY INVISIBLE (4800 6075);
FORCEPROP 1 LASTPIN (4750 5975) $PN 1
J 0
(4760 5955);
DISPLAY 0.489362 (4760 5955);
PAINT MONO (4760 5955);
FORCEPROP 1 LASTPIN (4750 5775) $PN 2
J 0
(4760 5755);
DISPLAY 0.489362 (4760 5755);
PAINT MONO (4760 5755);
FORCEPROP 1 LAST PACK_TYPE C0805
J 0
(4800 5775);
DISPLAY 0.489362 (4800 5775);
PAINT SKYBLUE (4800 5775);
FORCEPROP 1 LAST VALUE 22UF
J 0
(4800 5975);
DISPLAY 0.489362 (4800 5975);
PAINT SKYBLUE (4800 5975);
FORCEPROP 1 LAST MATERIAL X6S
J 0
(4800 5825);
DISPLAY 0.489362 (4800 5825);
PAINT SKYBLUE (4800 5825);
FORCEPROP 1 LAST TOLERANCE 20%
J 0
(4800 5875);
DISPLAY 0.489362 (4800 5875);
PAINT SKYBLUE (4800 5875);
FORCEPROP 1 LAST VOLTAGE 16V
J 0
(4800 5925);
DISPLAY 0.489362 (4800 5925);
PAINT SKYBLUE (4800 5925);
FORCEPROP 2 LAST CDS_LIB pure_quanta
J 0
(4750 5875);
DISPLAY INVISIBLE (4750 5875);
FORCEPROP 1 LAST PATH I80
J 0
(4800 6025);
DISPLAY 0.978723 (4800 6025);
PAINT WHITE (4800 6025);
DISPLAY INVISIBLE (4800 6025);
FORCEPROP 1 LAST PART_NUMBER CH6223MEA01
J 0
(4800 5725);
DISPLAY 0.489362 (4800 5725);
PAINT SKYBLUE (4800 5725);
DISPLAY INVISIBLE (4800 5725);
FORCEADD Q_CAP..1
(4425 5875);
FORCEPROP 1 LAST LOCATION PC152_1
J 0
(4475 6025);
DISPLAY 0.489362 (4475 6025);
PAINT SKYBLUE (4475 6025);
FORCEPROP 0 LAST $SEC 1
J 0
(4475 6075);
DISPLAY 0.680851 (4475 6075);
PAINT MONO (4475 6075);
DISPLAY INVISIBLE (4475 6075);
FORCEPROP 0 LAST CDS_SEC 1
J 0
(4475 6075);
DISPLAY 1.021277 (4475 6075);
DISPLAY INVISIBLE (4475 6075);
FORCEPROP 1 LASTPIN (4425 5975) $PN 1
J 0
(4435 5955);
DISPLAY 0.489362 (4435 5955);
PAINT MONO (4435 5955);
FORCEPROP 1 LASTPIN (4425 5775) $PN 2
J 0
(4435 5755);
DISPLAY 0.489362 (4435 5755);
PAINT MONO (4435 5755);
FORCEPROP 1 LAST VALUE 22UF
J 0
(4475 5975);
DISPLAY 0.489362 (4475 5975);
PAINT SKYBLUE (4475 5975);
FORCEPROP 1 LAST VOLTAGE 16V
J 0
(4475 5925);
DISPLAY 0.489362 (4475 5925);
PAINT SKYBLUE (4475 5925);
FORCEPROP 1 LAST MATERIAL X6S
J 0
(4475 5825);
DISPLAY 0.489362 (4475 5825);
PAINT SKYBLUE (4475 5825);
FORCEPROP 1 LAST PACK_TYPE C0805
J 0
(4475 5775);
DISPLAY 0.489362 (4475 5775);
PAINT SKYBLUE (4475 5775);
FORCEPROP 1 LAST TOLERANCE 20%
J 0
(4475 5875);
DISPLAY 0.489362 (4475 5875);
PAINT SKYBLUE (4475 5875);
FORCEPROP 2 LAST CDS_LIB pure_quanta
J 0
(4425 5875);
DISPLAY INVISIBLE (4425 5875);
FORCEPROP 1 LAST PATH I81
J 0
(4475 6025);
DISPLAY 0.978723 (4475 6025);
PAINT WHITE (4475 6025);
DISPLAY INVISIBLE (4475 6025);
FORCEPROP 1 LAST PART_NUMBER CH6223MEA01
J 0
(4475 5725);
DISPLAY 0.489362 (4475 5725);
PAINT SKYBLUE (4475 5725);
DISPLAY INVISIBLE (4475 5725);
FORCEADD Q_CAP..1
(4025 5875);
FORCEPROP 1 LAST LOCATION PC150_1
J 0
(4075 6025);
DISPLAY 0.489362 (4075 6025);
PAINT SKYBLUE (4075 6025);
FORCEPROP 0 LAST $SEC 1
J 0
(4075 6075);
DISPLAY 0.680851 (4075 6075);
PAINT MONO (4075 6075);
DISPLAY INVISIBLE (4075 6075);
FORCEPROP 0 LAST CDS_SEC 1
J 0
(4075 6075);
DISPLAY 1.021277 (4075 6075);
DISPLAY INVISIBLE (4075 6075);
FORCEPROP 1 LASTPIN (4025 5975) $PN 1
J 0
(4035 5955);
DISPLAY 0.489362 (4035 5955);
PAINT MONO (4035 5955);
FORCEPROP 1 LASTPIN (4025 5775) $PN 2
J 0
(4035 5755);
DISPLAY 0.489362 (4035 5755);
PAINT MONO (4035 5755);
FORCEPROP 1 LAST VOLTAGE 25V
J 0
(4075 5925);
DISPLAY 0.489362 (4075 5925);
PAINT SKYBLUE (4075 5925);
FORCEPROP 1 LAST VALUE 1UF
J 0
(4075 5975);
DISPLAY 0.489362 (4075 5975);
PAINT SKYBLUE (4075 5975);
FORCEPROP 1 LAST TOLERANCE 10%
J 0
(4075 5875);
DISPLAY 0.489362 (4075 5875);
PAINT SKYBLUE (4075 5875);
FORCEPROP 1 LAST MATERIAL X6S
J 0
(4075 5825);
DISPLAY 0.489362 (4075 5825);
PAINT SKYBLUE (4075 5825);
FORCEPROP 1 LAST PACK_TYPE C0402
J 0
(4075 5775);
DISPLAY 0.489362 (4075 5775);
PAINT SKYBLUE (4075 5775);
FORCEPROP 2 LAST CDS_LIB pure_quanta
J 0
(4025 5875);
DISPLAY INVISIBLE (4025 5875);
FORCEPROP 1 LAST PATH I82
J 0
(4075 6025);
DISPLAY 0.978723 (4075 6025);
PAINT WHITE (4075 6025);
DISPLAY INVISIBLE (4075 6025);
FORCEPROP 1 LAST PART_NUMBER CH5104KEB02
J 0
(4075 5725);
DISPLAY 0.489362 (4075 5725);
PAINT SKYBLUE (4075 5725);
DISPLAY INVISIBLE (4075 5725);
FORCEADD Q_CAP..1
(3600 5875);
FORCEPROP 1 LAST LOCATION PC148_1
J 0
(3675 6025);
DISPLAY 0.489362 (3675 6025);
PAINT SKYBLUE (3675 6025);
FORCEPROP 0 LAST $SEC 1
J 0
(3650 6025);
DISPLAY 0.680851 (3650 6025);
PAINT MONO (3650 6025);
DISPLAY INVISIBLE (3650 6025);
FORCEPROP 0 LAST CDS_SEC 1
J 0
(3650 6025);
DISPLAY 1.021277 (3650 6025);
DISPLAY INVISIBLE (3650 6025);
FORCEPROP 1 LASTPIN (3600 5975) $PN 1
J 0
(3610 5955);
DISPLAY 0.489362 (3610 5955);
PAINT MONO (3610 5955);
FORCEPROP 1 LASTPIN (3600 5775) $PN 2
J 0
(3610 5755);
DISPLAY 0.489362 (3610 5755);
PAINT MONO (3610 5755);
FORCEPROP 1 LAST MATERIAL X7R
J 0
(3675 5825);
DISPLAY 0.489362 (3675 5825);
PAINT SKYBLUE (3675 5825);
FORCEPROP 1 LAST TOLERANCE 10%
J 0
(3675 5875);
DISPLAY 0.489362 (3675 5875);
PAINT SKYBLUE (3675 5875);
FORCEPROP 1 LAST VALUE 0.1UF
J 0
(3675 5975);
DISPLAY 0.489362 (3675 5975);
PAINT SKYBLUE (3675 5975);
FORCEPROP 1 LAST VOLTAGE 25V
J 0
(3675 5925);
DISPLAY 0.489362 (3675 5925);
PAINT SKYBLUE (3675 5925);
FORCEPROP 1 LAST PACK_TYPE 0402
J 0
(3675 5725);
DISPLAY 0.489362 (3675 5725);
PAINT SKYBLUE (3675 5725);
FORCEPROP 2 LAST CDS_LIB pure_quanta
J 0
(3600 5875);
DISPLAY INVISIBLE (3600 5875);
FORCEPROP 1 LAST PATH I83
J 0
(3650 6025);
DISPLAY 0.978723 (3650 6025);
PAINT WHITE (3650 6025);
DISPLAY INVISIBLE (3650 6025);
FORCEPROP 1 LAST PART_NUMBER CH4104K1B00
J 0
(3675 5775);
DISPLAY 0.489362 (3675 5775);
PAINT SKYBLUE (3675 5775);
DISPLAY INVISIBLE (3675 5775);
FORCEADD ISL99390FRZTR5935..1
(2850 4975);
FORCEPROP 1 LAST LOCATION PU17
J 0
(2550 5850);
DISPLAY 0.489362 (2550 5850);
PAINT SKYBLUE (2550 5850);
FORCEPROP 0 LAST $SEC 1
J 0
(2550 6050);
DISPLAY 0.680851 (2550 6050);
PAINT MONO (2550 6050);
DISPLAY INVISIBLE (2550 6050);
FORCEPROP 2 LAST CDS_SEC 1
J 0
(2600 5975);
DISPLAY 1.021277 (2600 5975);
DISPLAY INVISIBLE (2600 5975);
FORCEPROP 0 LASTPIN (3250 4525) $PN 2
J 0
(3260 4535);
DISPLAY 0.489362 (3260 4535);
PAINT MONO (3260 4535);
FORCEPROP 0 LASTPIN (3250 5325) $PN 33
J 0
(3260 5335);
DISPLAY 0.489362 (3260 5335);
PAINT MONO (3260 5335);
FORCEPROP 0 LASTPIN (2400 4725) $PN 31
J 2
(2390 4735);
DISPLAY 0.489362 (2390 4735);
PAINT MONO (2390 4735);
FORCEPROP 0 LASTPIN (2400 5125) $PN 35
J 2
(2390 5135);
DISPLAY 0.489362 (2390 5135);
PAINT MONO (2390 5135);
FORCEPROP 0 LASTPIN (3250 4675) $PN 6
J 0
(3260 4685);
DISPLAY 0.489362 (3260 4685);
PAINT MONO (3260 4685);
FORCEPROP 0 LASTPIN (3250 4625) $PN 41
J 0
(3260 4635);
DISPLAY 0.489362 (3260 4635);
PAINT MONO (3260 4635);
FORCEPROP 0 LASTPIN (2400 4975) $PN 38
J 2
(2390 4985);
DISPLAY 0.489362 (2390 4985);
PAINT MONO (2390 4985);
FORCEPROP 0 LASTPIN (2400 4675) $PN 37
J 2
(2390 4685);
DISPLAY 0.489362 (2390 4685);
PAINT MONO (2390 4685);
FORCEPROP 0 LASTPIN (3250 4475) $PN 5
J 0
(3260 4485);
DISPLAY 0.489362 (3260 4485);
PAINT MONO (3260 4485);
FORCEPROP 0 LASTPIN (3250 4425) $PN 7_9-20_24
J 0
(3260 4435);
DISPLAY 0.489362 (3260 4435);
PAINT MONO (3260 4435);
FORCEPROP 0 LASTPIN (3250 4375) $PN 40
J 0
(3260 4385);
DISPLAY 0.489362 (3260 4385);
PAINT MONO (3260 4385);
FORCEPROP 0 LASTPIN (3250 5075) $PN 32
J 0
(3260 5085);
DISPLAY 0.489362 (3260 5085);
PAINT MONO (3260 5085);
FORCEPROP 0 LASTPIN (2400 5625) $PN 4
J 2
(2390 5635);
DISPLAY 0.489362 (2390 5635);
PAINT MONO (2390 5635);
FORCEPROP 0 LASTPIN (2400 4375) $PN 34
J 2
(2390 4385);
DISPLAY 0.489362 (2390 4385);
PAINT MONO (2390 4385);
FORCEPROP 0 LASTPIN (2400 4875) $PN 39
J 2
(2390 4885);
DISPLAY 0.489362 (2390 4885);
PAINT MONO (2390 4885);
FORCEPROP 0 LASTPIN (3250 4975) $PN 10_19
J 0
(3260 4985);
DISPLAY 0.489362 (3260 4985);
PAINT MONO (3260 4985);
FORCEPROP 0 LASTPIN (2400 4475) $PN 36
J 2
(2390 4485);
DISPLAY 0.489362 (2390 4485);
PAINT MONO (2390 4485);
FORCEPROP 0 LASTPIN (2400 5325) $PN 3
J 2
(2390 5335);
DISPLAY 0.489362 (2390 5335);
PAINT MONO (2390 5335);
FORCEPROP 0 LASTPIN (3250 5625) $PN 25_29
J 0
(3260 5635);
DISPLAY 0.489362 (3260 5635);
PAINT MONO (3260 5635);
FORCEPROP 0 LASTPIN (3250 5575) $PN 30
J 0
(3260 5585);
DISPLAY 0.489362 (3260 5585);
PAINT MONO (3260 5585);
FORCEPROP 0 LASTPIN (3250 4725) $PN 1
J 0
(3260 4735);
DISPLAY 0.489362 (3260 4735);
PAINT MONO (3260 4735);
FORCEPROP 2 LAST VALUE ISL99390FRZ-TR5935
J 0
(2550 5950);
DISPLAY 0.489362 (2550 5950);
PAINT SKYBLUE (2550 5950);
FORCEPROP 1 LAST MATERIAL IC
J 0
(2550 5700);
DISPLAY 0.489362 (2550 5700);
PAINT SKYBLUE (2550 5700);
FORCEPROP 2 LAST PART_TYPE SMLF
J 0
(2550 6000);
DISPLAY 0.638298 (2550 6000);
FORCEPROP 1 LAST CDS_LMAN_SYM_OUTLINE -300,700,250,-650
J 0
(2850 4975);
DISPLAY 0.468085 (2850 4975);
PAINT GREEN (2850 4975);
DISPLAY INVISIBLE (2850 4975);
FORCEPROP 1 LAST NEEDS_NO_SIZE TRUE
J 0
(2850 4975);
DISPLAY 0.723404 (2850 4975);
PAINT GREEN (2850 4975);
DISPLAY INVISIBLE (2850 4975);
FORCEPROP 2 LAST CDS_LIB pure_quanta
J 0
(2850 4975);
DISPLAY INVISIBLE (2850 4975);
FORCEPROP 1 LAST PATH I84
J 0
(2850 4975);
DISPLAY 0.723404 (2850 4975);
PAINT GREEN (2850 4975);
DISPLAY INVISIBLE (2850 4975);
FORCEPROP 1 LAST PART_NUMBER AL099390004
J 0
(2550 5775);
DISPLAY 0.489362 (2550 5775);
PAINT SKYBLUE (2550 5775);
DISPLAY INVISIBLE (2550 5775);
FORCEADD Q_CAP..1
(5425 5900);
FORCEPROP 1 LAST LOCATION PC7000
J 0
(5475 6000);
DISPLAY 0.510638 (5475 6000);
FORCEPROP 0 LAST $SEC 1
J 0
(5475 6025);
DISPLAY 0.680851 (5475 6025);
PAINT MONO (5475 6025);
DISPLAY INVISIBLE (5475 6025);
FORCEPROP 0 LAST CDS_SEC 1
J 0
(5475 6025);
DISPLAY 0.680851 (5475 6025);
DISPLAY INVISIBLE (5475 6025);
FORCEPROP 1 LASTPIN (5425 6000) $PN 1
J 0
(5435 5980);
DISPLAY 0.787234 (5435 5980);
PAINT MONO (5435 5980);
FORCEPROP 1 LASTPIN (5425 5800) $PN 2
J 0
(5435 5780);
DISPLAY 0.787234 (5435 5780);
PAINT MONO (5435 5780);
FORCEPROP 1 LAST PACK_TYPE C0805
J 0
(5475 5700);
DISPLAY 0.510638 (5475 5700);
FORCEPROP 1 LAST MATERIAL X6S
J 0
(5475 5800);
DISPLAY 0.510638 (5475 5800);
FORCEPROP 1 LAST TOLERANCE 20%
J 0
(5475 5850);
DISPLAY 0.510638 (5475 5850);
FORCEPROP 1 LAST VOLTAGE 16V
J 0
(5475 5900);
DISPLAY 0.510638 (5475 5900);
FORCEPROP 1 LAST VALUE 22UF
J 0
(5475 5950);
DISPLAY 0.510638 (5475 5950);
FORCEPROP 2 LAST CDS_LIB pure_quanta
J 0
(5425 5900);
DISPLAY INVISIBLE (5425 5900);
FORCEPROP 1 LAST PATH I85
J 0
(5475 6050);
DISPLAY 0.978723 (5475 6050);
PAINT WHITE (5475 6050);
DISPLAY INVISIBLE (5475 6050);
FORCEPROP 1 LAST PART_NUMBER CH6223MEA01
J 0
(5475 5750);
DISPLAY 0.404255 (5475 5750);
DISPLAY INVISIBLE (5475 5750);
FORCEADD UNIVERSAL_GND..1
(1175 2375);
FORCEPROP 3 LASTPIN (1175 2425) SIG_NAME GND\g
J 0
(1185 2435);
DISPLAY 0.659574 (1185 2435);
PAINT MONO (1185 2435);
DISPLAY INVISIBLE (1185 2435);
FORCEPROP 2 LAST CDS_LIB pure_quanta_power
J 0
(1175 2375);
DISPLAY INVISIBLE (1175 2375);
FORCEPROP 1 LAST HDL_POWER GND
J 1
(1200 2300);
DISPLAY 0.872340 (1200 2300);
PAINT GREEN (1200 2300);
DISPLAY INVISIBLE (1200 2300);
FORCEPROP 1 LAST PATH I9
J 0
(1250 2375);
DISPLAY 0.872340 (1250 2375);
PAINT AQUA (1250 2375);
DISPLAY INVISIBLE (1250 2375);
FORCEADD DNS..1
(4300 1475);
PAINT RED (4300 1475);
FORCEPROP 2 LAST CDS_LIB mstr_misc
J 0
(4300 1475);
DISPLAY INVISIBLE (4300 1475);
FORCEPROP 1 LAST COMMENT_BODY TRUE
R 1
J 0
(4375 1250);
DISPLAY 0.872340 (4375 1250);
PAINT GREEN (4375 1250);
DISPLAY INVISIBLE (4375 1250);
FORCEADD DNS..1
(4300 1975);
PAINT RED (4300 1975);
FORCEPROP 2 LAST CDS_LIB mstr_misc
J 0
(4300 1975);
DISPLAY INVISIBLE (4300 1975);
FORCEPROP 1 LAST COMMENT_BODY TRUE
R 1
J 0
(4375 1750);
DISPLAY 0.872340 (4375 1750);
PAINT GREEN (4375 1750);
DISPLAY INVISIBLE (4375 1750);
FORCEADD DNS..1
(7150 3150);
PAINT RED (7150 3150);
FORCEPROP 2 LAST CDS_LIB mstr_misc
J 0
(7150 3150);
DISPLAY INVISIBLE (7150 3150);
FORCEPROP 1 LAST COMMENT_BODY TRUE
R 1
J 0
(7225 2925);
DISPLAY 0.872340 (7225 2925);
PAINT GREEN (7225 2925);
DISPLAY INVISIBLE (7225 2925);
FORCEADD DNS..1
(4300 4225);
PAINT RED (4300 4225);
FORCEPROP 2 LAST CDS_LIB mstr_misc
J 0
(4300 4225);
DISPLAY INVISIBLE (4300 4225);
FORCEPROP 1 LAST COMMENT_BODY TRUE
R 1
J 0
(4375 4000);
DISPLAY 0.872340 (4375 4000);
PAINT GREEN (4375 4000);
DISPLAY INVISIBLE (4375 4000);
FORCEADD DNS..1
(4300 4775);
PAINT RED (4300 4775);
FORCEPROP 2 LAST CDS_LIB mstr_misc
J 0
(4300 4775);
DISPLAY INVISIBLE (4300 4775);
FORCEPROP 1 LAST COMMENT_BODY TRUE
R 1
J 0
(4375 4550);
DISPLAY 0.872340 (4375 4550);
PAINT GREEN (4375 4550);
DISPLAY INVISIBLE (4375 4550);
FORCEADD DNS..1
(875 4500);
PAINT RED (875 4500);
FORCEPROP 2 LAST CDS_LIB mstr_misc
J 0
(875 4500);
PAINT MONO (875 4500);
DISPLAY INVISIBLE (875 4500);
FORCEPROP 1 LAST COMMENT_BODY TRUE
R 1
J 0
(950 4275);
DISPLAY 0.872340 (950 4275);
PAINT GREEN (950 4275);
DISPLAY INVISIBLE (950 4275);
FORCEADD DNS..1
(850 1650);
PAINT RED (850 1650);
FORCEPROP 2 LAST CDS_LIB mstr_misc
J 0
(850 1650);
PAINT MONO (850 1650);
DISPLAY INVISIBLE (850 1650);
FORCEPROP 1 LAST COMMENT_BODY TRUE
R 1
J 0
(925 1425);
DISPLAY 0.872340 (925 1425);
PAINT GREEN (925 1425);
DISPLAY INVISIBLE (925 1425);
FORCEADD QUANTA_TITLE_BLOCK_C..1
(8900 -75);
FORCEPROP 0 LAST CDS_CON_LAST_MODIFIED Thu Sep 14 16:12:41 2023
J 0
(7015 -60);
DISPLAY INVISIBLE (7015 -60);
FORCEPROP 1 LAST CUSTOM_TXT_CDS <CON_LAST_MODIFIED>
J 0
(7015 -60);
DISPLAY 0.978723 (7015 -60);
FORCEPROP 2 LAST CUSTOM_TXT_CDS <XR_PAGE_TITLE>
J 0
(1010 5175);
DISPLAY 0.638298 (1010 5175);
PAINT PINK (1010 5175);
DISPLAY INVISIBLE (1010 5175);
FORCEPROP 1 LAST CUSTOM_TXT_CDS <NAME_2>
J 0
(5725 -25);
FORCEPROP 1 LAST CUSTOM_TXT_CDS <NAME_1>
J 0
(5725 100);
FORCEPROP 1 LAST CUSTOM_TXT_CDS <Q_NUMBER>
J 0
(7497 28);
DISPLAY 1.212766 (7497 28);
FORCEPROP 1 LAST CUSTOM_TXT_CDS <Q_PROJ>
J 0
(6518 27);
DISPLAY 1.212766 (6518 27);
FORCEPROP 1 LAST CUSTOM_TXT_CDS <Q_REV>
J 0
(8716 28);
DISPLAY 1.212766 (8716 28);
FORCEPROP 1 LAST CUSTOM_TXT_CDS <CON_PAGE_NUM> OF <CON_TOTAL_PAGES>
J 0
(8454 -57);
DISPLAY 0.978723 (8454 -57);
FORCEPROP 1 LAST Q_TITLE PVDDIO_P0_VR PHASE 1&2
J 0
(-400 -25);
DISPLAY 2.446809 (-400 -25);
PAINT GREEN (-400 -25);
FORCEPROP 2 LAST CDS_LIB pure_quanta
J 0
(8900 -75);
DISPLAY INVISIBLE (8900 -75);
FORCEPROP 1 LAST CDS_LMAN_SYM_OUTLINE -9475,6775,100,-125
J 0
(8900 -75);
DISPLAY 0.468085 (8900 -75);
PAINT GREEN (8900 -75);
DISPLAY INVISIBLE (8900 -75);
FORCEPROP 2 LAST PAGE_BORDER TRUE
J 0
(1010 5175);
DISPLAY 0.638298 (1010 5175);
PAINT PINK (1010 5175);
DISPLAY INVISIBLE (1010 5175);
FORCEPROP 2 LAST CDS_XR_PAGE_TITLE CR-205 : @T6G_MB_LIB.T6G(SCH_1):PAGE205
J 0
(1010 5175);
DISPLAY 0.638298 (1010 5175);
PAINT PINK (1010 5175);
DISPLAY INVISIBLE (1010 5175);
FORCEPROP 1 LAST Q_DEPT BU9
J 1
(5137 -26);
DISPLAY 1.957447 (5137 -26);
PAINT GREEN (5137 -26);
DISPLAY INVISIBLE (5137 -26);
FORCEPROP 1 LAST COMMENT_BODY TRUE
J 0
(8912 -88);
DISPLAY 0.978723 (8912 -88);
PAINT GREEN (8912 -88);
DISPLAY INVISIBLE (8912 -88);
WIRE 16 -1 (275 1650)(275 1700);
WIRE 16 -1 (1525 3050)(1525 2925);
WIRE 16 -1 (250 4400)(250 4500);
WIRE 16 -1 (875 4425)(875 4350);
WIRE 16 -1 (1275 5150)(1275 5100);
WIRE 16 -1 (850 1575)(850 1500);
WIRE 16 -1 (1625 5725)(1625 5600);
WIRE 16 -1 (4325 1375)(4325 1300);
WIRE 16 -1 (4325 4125)(4325 4050);
WIRE 16 -1 (6600 5825)(6600 5650);
WIRE 16 -1 (1175 2475)(1175 2425);
WIRE 16 -1 (2400 1675)(1350 1675);
FORCEPROP 2 LAST SIG_NAME PVDDIO_P0_TEMP1
J 0
(1415 1685);
DISPLAY 0.489362 (1415 1685);
WIRE 16 -1 (2400 1575)(1350 1575);
FORCEPROP 2 LAST SIG_NAME PVDDIO_P0_PWM2
J 0
(1415 1585);
DISPLAY 0.489362 (1415 1585);
WIRE 16 -1 (1975 1925)(2400 1925);
FORCEPROP 2 LAST SIG_NAME NC_PVDDIO_P0_DNC2
J 0
(1880 1935);
DISPLAY 0.489362 (1880 1935);
FORCEPROP 2 LASTPROP $XRERR UNIQUE?
J 0
(1735 1925);
DISPLAY 0.638298 (1735 1925);
PAINT MONO (1735 1925);
DISPLAY INVISIBLE (1735 1925);
WIRE 16 -1 (2250 2075)(2250 2000);
FORCEPROP 0 LAST CDS_PHYS_NET_NAME PVDDCR_CPU1_P0_VCCS
J 0
(2250 2025);
PAINT MONO (2250 2025);
DISPLAY INVISIBLE (2250 2025);
WIRE 16 -1 (2250 2075)(2400 2075);
WIRE 16 -1 (1350 2075)(2250 2075);
FORCEPROP 2 LAST SIG_NAME PVDDCR_CPU1_P0_VCCS
J 0
(1415 2085);
DISPLAY 0.489362 (1415 2085);
WIRE 16 -1 (2250 2000)(275 2000);
WIRE 16 -1 (275 2000)(275 1900);
WIRE 16 -1 (2400 2175)(1350 2175);
FORCEPROP 2 LAST SIG_NAME PVDDIO_P0_IMON2
J 0
(1415 2185);
DISPLAY 0.489362 (1415 2185);
WIRE 16 -1 (3425 6125)(3425 5625);
WIRE 16 -1 (3600 6125)(3425 6125);
WIRE 16 -1 (3425 5625)(3425 5575);
WIRE 16 -1 (3250 5625)(3425 5625);
WIRE 16 -1 (3425 5575)(3250 5575);
WIRE 16 -1 (4025 6125)(3600 6125);
WIRE 16 -1 (3600 5975)(3600 6125);
WIRE 16 -1 (4025 6125)(4425 6125);
WIRE 16 -1 (4025 5975)(4025 6125);
WIRE 16 -1 (4425 6125)(4750 6125);
WIRE 16 -1 (4425 6125)(4425 5975);
WIRE 16 -1 (5075 6125)(4750 6125);
WIRE 16 -1 (4750 5975)(4750 6125);
WIRE 16 -1 (5425 6125)(5075 6125);
WIRE 16 -1 (5075 6125)(5075 6000);
WIRE 16 -1 (5450 6125)(5425 6125);
WIRE 16 -1 (5425 6125)(5425 6000);
WIRE 16 -1 (5450 6200)(5450 6125);
WIRE 16 -1 (5450 6125)(5725 6125);
WIRE 16 -1 (5725 6125)(5975 6125);
WIRE 16 -1 (5725 6000)(5725 6125);
WIRE 16 -1 (3600 5775)(3600 5625);
WIRE 16 -1 (3600 5625)(4025 5625);
WIRE 16 -1 (4425 5625)(4025 5625);
WIRE 16 -1 (4025 5775)(4025 5625);
WIRE 16 -1 (4425 5625)(4750 5625);
WIRE 16 -1 (4425 5775)(4425 5625);
WIRE 16 -1 (4750 5775)(4750 5625);
WIRE 16 -1 (5075 5625)(4750 5625);
WIRE 16 -1 (5425 5625)(5075 5625);
WIRE 16 -1 (5075 5800)(5075 5625);
WIRE 16 -1 (5425 5800)(5425 5625);
WIRE 16 -1 (5450 5625)(5425 5625);
WIRE 16 -1 (5725 5625)(5450 5625);
WIRE 16 -1 (5450 5575)(5450 5625);
WIRE 16 -1 (5725 5625)(5725 5800);
WIRE 16 -1 (7200 4975)(7100 4975);
WIRE 16 -1 (7700 4975)(7200 4975);
WIRE 16 -1 (7200 4875)(7200 4975);
WIRE 16 -1 (7100 4975)(6450 4975);
WIRE 16 -1 (7100 4975)(7100 3875);
WIRE 16 -1 (7100 3875)(5550 3875);
WIRE 16 -1 (7700 4975)(8125 4975);
WIRE 16 -1 (7700 4975)(7700 4875);
WIRE 16 -1 (8425 4975)(8125 4975);
WIRE 16 -1 (8125 4875)(8125 4975);
WIRE 16 -1 (8425 4975)(8425 4875);
WIRE 16 -1 (8425 5050)(8425 4975);
WIRE 16 -1 (7200 4675)(7200 4550);
WIRE 16 -1 (7700 4550)(7200 4550);
WIRE 16 -1 (7700 4550)(7700 4675);
WIRE 16 -1 (8125 4550)(7700 4550);
WIRE 16 -1 (8425 4550)(8125 4550);
WIRE 16 -1 (8125 4675)(8125 4550);
WIRE 16 -1 (8425 4675)(8425 4550);
WIRE 16 -1 (8425 4475)(8425 4550);
WIRE 16 -1 (6600 6200)(6600 6125);
WIRE 16 -1 (6600 6125)(6600 6025);
WIRE 16 -1 (6600 6125)(6175 6125);
WIRE 16 -1 (6450 4725)(6925 4725);
WIRE 16 -1 (6925 4650)(6925 4725);
WIRE 16 -1 (7150 3275)(7150 3400);
WIRE 16 -1 (7150 3400)(7550 3400);
WIRE 16 -1 (7550 3400)(7950 3400);
WIRE 16 -1 (7550 3275)(7550 3400);
WIRE 16 -1 (7950 3450)(7950 3400);
WIRE 16 -1 (7950 3400)(7950 3275);
WIRE 16 -1 (7550 3075)(7550 2975);
WIRE 16 -1 (7550 2975)(7950 2975);
WIRE 16 -1 (7150 2975)(7550 2975);
WIRE 16 -1 (7150 3075)(7150 2975);
WIRE 16 -1 (7950 3075)(7950 2975);
WIRE 16 -1 (7950 2975)(7950 2875);
WIRE 16 -1 (7300 1150)(7300 2175);
WIRE 16 -1 (7300 1150)(5550 1150);
WIRE 16 -1 (7650 2175)(7300 2175);
WIRE 16 -1 (6625 2175)(7300 2175);
WIRE 16 -1 (7650 2175)(8075 2175);
WIRE 16 -1 (7650 2175)(7650 2075);
WIRE 16 -1 (8075 2275)(8075 2175);
WIRE 16 -1 (8075 2075)(8075 2175);
WIRE 16 -1 (8075 1875)(8075 1750);
WIRE 16 -1 (8075 1675)(8075 1750);
WIRE 16 -1 (8075 1750)(7650 1750);
WIRE 16 -1 (7650 1750)(7650 1875);
WIRE 16 -1 (3425 3350)(3425 2825);
WIRE 16 -1 (3675 3350)(3425 3350);
WIRE 16 -1 (3425 2825)(3425 2775);
WIRE 16 -1 (3250 2825)(3425 2825);
WIRE 16 -1 (3425 2775)(3250 2775);
WIRE 16 -1 (4175 3350)(3675 3350);
WIRE 16 -1 (3675 3200)(3675 3350);
WIRE 16 -1 (4175 3350)(4575 3350);
WIRE 16 -1 (4175 3200)(4175 3350);
WIRE 16 -1 (4575 3350)(4975 3350);
WIRE 16 -1 (4575 3350)(4575 3200);
WIRE 16 -1 (5450 3350)(4975 3350);
WIRE 16 -1 (4975 3200)(4975 3350);
WIRE 16 -1 (5450 3425)(5450 3350);
WIRE 16 -1 (5450 3200)(5450 3350);
WIRE 16 -1 (3675 3000)(3675 2850);
WIRE 16 -1 (3675 2850)(4175 2850);
WIRE 16 -1 (4575 2850)(4175 2850);
WIRE 16 -1 (4175 3000)(4175 2850);
WIRE 16 -1 (4575 2850)(4975 2850);
WIRE 16 -1 (4575 3000)(4575 2850);
WIRE 16 -1 (5450 2850)(4975 2850);
WIRE 16 -1 (4975 3000)(4975 2850);
WIRE 16 -1 (5450 3000)(5450 2850);
WIRE 16 -1 (5450 2800)(5450 2850);
WIRE 16 -1 (3250 4425)(3500 4425);
WIRE 16 -1 (3500 4475)(3500 4425);
WIRE 16 -1 (3500 4425)(3500 4375);
WIRE 16 -1 (3250 4375)(3500 4375);
WIRE 16 -1 (3500 4375)(3500 4300);
WIRE 16 -1 (3500 4475)(3500 4525);
WIRE 16 -1 (3250 4475)(3500 4475);
WIRE 16 -1 (3500 4525)(3250 4525);
WIRE 16 -1 (1950 5625)(2400 5625);
WIRE 16 -1 (1950 5625)(1950 6025);
WIRE 16 -1 (1950 6025)(1625 6025);
WIRE 16 -1 (1625 5925)(1625 6025);
WIRE 16 -1 (1625 6025)(1275 6025);
WIRE 16 -1 (1275 6175)(1275 6025);
WIRE 16 -1 (1275 5900)(1275 6025);
WIRE 16 -1 (3250 1625)(3500 1625);
WIRE 16 -1 (3500 1675)(3500 1625);
WIRE 16 -1 (3500 1625)(3500 1575);
WIRE 16 -1 (3250 1575)(3500 1575);
WIRE 16 -1 (3500 1575)(3500 1500);
WIRE 16 -1 (3500 1675)(3500 1725);
WIRE 16 -1 (3250 1675)(3500 1675);
WIRE 16 -1 (3500 1725)(3250 1725);
WIRE 16 -1 (1850 2825)(2400 2825);
WIRE 16 -1 (1850 2825)(1850 3350);
WIRE 16 -1 (1850 3350)(1525 3350);
WIRE 16 -1 (1525 3250)(1525 3350);
WIRE 16 -1 (1525 3350)(1175 3350);
WIRE 16 -1 (1175 3500)(1175 3350);
WIRE 16 -1 (1175 3225)(1175 3350);
WIRE 16 -1 (5350 3875)(4075 3875);
WIRE 16 -1 (4075 4725)(4075 3875);
WIRE 16 -1 (3250 4725)(4075 4725);
FORCEPROP 2 LAST SIG_NAME PVDDIO_P0_VOS1
J 0
(3365 4750);
DISPLAY 0.489362 (3365 4750);
FORCEPROP 2 LASTPROP $XRERR UNIQUE?
J 0
(3125 4750);
DISPLAY 0.638298 (3125 4750);
PAINT MONO (3125 4750);
DISPLAY INVISIBLE (3125 4750);
WIRE 16 -1 (4325 4875)(4325 4975);
WIRE 16 -1 (4325 4975)(5650 4975);
WIRE 16 -1 (3250 4975)(4325 4975);
FORCEPROP 2 LAST SIG_NAME SW_PVDDIO_P0_SW1
J 0
(3440 4985);
DISPLAY 0.489362 (3440 4985);
FORCEPROP 2 LASTPROP $XRERR UNIQUE?
J 0
(3200 4985);
DISPLAY 0.638298 (3200 4985);
PAINT MONO (3200 4985);
DISPLAY INVISIBLE (3200 4985);
WIRE 16 -1 (4850 5075)(4850 5100);
WIRE 16 -1 (3250 5075)(4850 5075);
FORCEPROP 2 LAST SIG_NAME SW_PVDDIO_P0_BOOTR1
J 0
(3440 5085);
DISPLAY 0.489362 (3440 5085);
FORCEPROP 2 LASTPROP $XRERR UNIQUE?
J 0
(3200 5085);
DISPLAY 0.638298 (3200 5085);
PAINT MONO (3200 5085);
DISPLAY INVISIBLE (3200 5085);
WIRE 16 -1 (3250 5325)(3850 5325);
FORCEPROP 2 LAST SIG_NAME SW_PVDDIO_P0_BOOT1
J 0
(3440 5335);
DISPLAY 0.489362 (3440 5335);
FORCEPROP 2 LASTPROP $XRERR UNIQUE?
J 0
(3200 5335);
DISPLAY 0.638298 (3200 5335);
PAINT MONO (3200 5335);
DISPLAY INVISIBLE (3200 5335);
WIRE 16 -1 (875 4675)(2400 4675);
FORCEPROP 0 LAST CDS_PHYS_NET_NAME PVDDIO_P0_LSET1
J 0
(1465 4715);
PAINT MONO (1465 4715);
DISPLAY INVISIBLE (1465 4715);
FORCEPROP 2 LAST SIG_NAME PVDDIO_P0_LSET1
J 0
(1465 4685);
DISPLAY 0.489362 (1465 4685);
FORCEPROP 2 LASTPROP $XRERR UNIQUE?
J 0
(1225 4685);
DISPLAY 0.638298 (1225 4685);
PAINT MONO (1225 4685);
DISPLAY INVISIBLE (1225 4685);
WIRE 16 -1 (875 4675)(875 4625);
WIRE 16 -1 (2400 4475)(1375 4475);
FORCEPROP 2 LAST SIG_NAME PVDDIO_P0_TEMP1
J 0
(1440 4485);
DISPLAY 0.489362 (1440 4485);
WIRE 16 -1 (2400 4375)(1375 4375);
FORCEPROP 2 LAST SIG_NAME PVDDIO_P0_PWM1
J 0
(1440 4385);
DISPLAY 0.489362 (1440 4385);
WIRE 16 -1 (4850 5325)(4850 5300);
WIRE 16 -1 (4050 5325)(4850 5325);
FORCEPROP 2 LAST SIG_NAME SW_PVDDIO_P0_BOOT1_R
J 0
(4140 5335);
DISPLAY 0.489362 (4140 5335);
FORCEPROP 2 LASTPROP $XRERR UNIQUE?
J 0
(3900 5335);
DISPLAY 0.638298 (3900 5335);
PAINT MONO (3900 5335);
DISPLAY INVISIBLE (3900 5335);
WIRE 16 -1 (3250 2525)(4025 2525);
FORCEPROP 2 LAST SIG_NAME SW_PVDDIO_P0_BOOT2
J 0
(3415 2535);
DISPLAY 0.489362 (3415 2535);
FORCEPROP 2 LASTPROP $XRERR UNIQUE?
J 0
(3175 2535);
DISPLAY 0.638298 (3175 2535);
PAINT MONO (3175 2535);
DISPLAY INVISIBLE (3175 2535);
WIRE 16 -1 (4850 2525)(4850 2500);
WIRE 16 -1 (4225 2525)(4850 2525);
FORCEPROP 2 LAST SIG_NAME SW_PVDDIO_P0_BOOT2_R
J 0
(4440 2535);
DISPLAY 0.489362 (4440 2535);
FORCEPROP 2 LASTPROP $XRERR UNIQUE?
J 0
(4200 2535);
DISPLAY 0.638298 (4200 2535);
PAINT MONO (4200 2535);
DISPLAY INVISIBLE (4200 2535);
WIRE 16 -1 (850 1875)(2400 1875);
FORCEPROP 2 LAST SIG_NAME PVDDIO_P0_LSET2
J 0
(1440 1885);
DISPLAY 0.489362 (1440 1885);
FORCEPROP 2 LASTPROP $XRERR UNIQUE?
J 0
(1200 1885);
DISPLAY 0.638298 (1200 1885);
PAINT MONO (1200 1885);
DISPLAY INVISIBLE (1200 1885);
WIRE 16 -1 (850 1875)(850 1775);
WIRE 16 -1 (3250 1825)(3825 1825);
FORCEPROP 2 LAST SIG_NAME NC_PVDDIO_P0_GL2_2
J 0
(3440 1835);
DISPLAY 0.489362 (3440 1835);
FORCEPROP 2 LASTPROP $XRERR UNIQUE?
J 0
(3855 1825);
DISPLAY 0.638298 (3855 1825);
PAINT MONO (3855 1825);
DISPLAY INVISIBLE (3855 1825);
WIRE 16 -1 (3250 1875)(3825 1875);
FORCEPROP 2 LAST SIG_NAME NC_PVDDIO_P0_GL1_2
J 0
(3440 1885);
DISPLAY 0.489362 (3440 1885);
FORCEPROP 2 LASTPROP $XRERR UNIQUE?
J 0
(3855 1875);
DISPLAY 0.638298 (3855 1875);
PAINT MONO (3855 1875);
DISPLAY INVISIBLE (3855 1875);
WIRE 16 -1 (5350 1150)(4000 1150);
WIRE 16 -1 (4000 1925)(4000 1150);
WIRE 16 -1 (3250 1925)(4000 1925);
FORCEPROP 2 LAST SIG_NAME PVDDIO_P0_VOS2
J 0
(3440 1950);
DISPLAY 0.489362 (3440 1950);
FORCEPROP 2 LASTPROP $XRERR UNIQUE?
J 0
(3200 1950);
DISPLAY 0.638298 (3200 1950);
PAINT MONO (3200 1950);
DISPLAY INVISIBLE (3200 1950);
WIRE 16 -1 (1175 2750)(1575 2750);
WIRE 16 -1 (1175 3025)(1175 2750);
WIRE 16 -1 (1175 2750)(1175 2675);
WIRE 16 -1 (1575 2750)(1575 2525);
WIRE 16 -1 (2250 2525)(1575 2525);
FORCEPROP 0 LAST CDS_PHYS_NET_NAME PVDDIO_P0_VCC2
J 0
(1640 2565);
PAINT MONO (1640 2565);
DISPLAY INVISIBLE (1640 2565);
FORCEPROP 2 LAST SIG_NAME PVDDIO_P0_VCC2
J 0
(1615 2535);
DISPLAY 0.489362 (1615 2535);
FORCEPROP 2 LASTPROP $XRERR UNIQUE?
J 0
(1375 2535);
DISPLAY 0.638298 (1375 2535);
PAINT MONO (1375 2535);
DISPLAY INVISIBLE (1375 2535);
WIRE 16 -1 (2400 2525)(2250 2525);
WIRE 16 -1 (2250 2525)(2250 2325);
WIRE 16 -1 (2400 2325)(2250 2325);
WIRE 16 -1 (2250 4875)(2250 4800);
FORCEPROP 0 LAST CDS_PHYS_NET_NAME PVDDCR_CPU1_P0_VCCS
J 0
(2250 4825);
PAINT MONO (2250 4825);
DISPLAY INVISIBLE (2250 4825);
WIRE 16 -1 (2250 4875)(2400 4875);
WIRE 16 -1 (1375 4875)(2250 4875);
FORCEPROP 2 LAST SIG_NAME PVDDCR_CPU1_P0_VCCS
J 0
(1565 4885);
DISPLAY 0.489362 (1565 4885);
WIRE 16 -1 (2250 4800)(250 4800);
WIRE 16 -1 (250 4800)(250 4700);
WIRE 16 -1 (2400 4975)(1375 4975);
FORCEPROP 2 LAST SIG_NAME PVDDIO_P0_IMON1
J 0
(1440 4985);
DISPLAY 0.489362 (1440 4985);
WIRE 16 -1 (2400 4725)(1975 4725);
FORCEPROP 2 LAST SIG_NAME NC_PVDDIO_P0_DNC1
J 0
(1905 4735);
DISPLAY 0.489362 (1905 4735);
FORCEPROP 2 LASTPROP $XRERR UNIQUE?
J 0
(1735 4725);
DISPLAY 0.638298 (1735 4725);
PAINT MONO (1735 4725);
DISPLAY INVISIBLE (1735 4725);
WIRE 16 -1 (1275 5425)(1850 5425);
WIRE 16 -1 (1275 5700)(1275 5425);
WIRE 16 -1 (1275 5425)(1275 5350);
WIRE 16 -1 (1850 5425)(1850 5325);
WIRE 16 -1 (2250 5325)(1850 5325);
FORCEPROP 0 LAST CDS_PHYS_NET_NAME PVDDIO_P0_VCC1
J 0
(1940 5365);
PAINT MONO (1940 5365);
DISPLAY INVISIBLE (1940 5365);
FORCEPROP 2 LAST SIG_NAME PVDDIO_P0_VCC1
J 0
(1915 5335);
DISPLAY 0.489362 (1915 5335);
FORCEPROP 2 LASTPROP $XRERR UNIQUE?
J 0
(1675 5335);
DISPLAY 0.638298 (1675 5335);
PAINT MONO (1675 5335);
DISPLAY INVISIBLE (1675 5335);
WIRE 16 -1 (2400 5325)(2250 5325);
WIRE 16 -1 (2250 5325)(2250 5125);
WIRE 16 -1 (2400 5125)(2250 5125);
WIRE 16 -1 (3825 4625)(3250 4625);
FORCEPROP 2 LAST SIG_NAME NC_PVDDIO_P0_GL2_1
J 0
(3365 4635);
DISPLAY 0.489362 (3365 4635);
FORCEPROP 2 LASTPROP $XRERR UNIQUE?
J 0
(3855 4625);
DISPLAY 0.638298 (3855 4625);
PAINT MONO (3855 4625);
DISPLAY INVISIBLE (3855 4625);
WIRE 16 -1 (3250 4675)(3825 4675);
FORCEPROP 2 LAST SIG_NAME NC_PVDDIO_P0_GL1_1
J 0
(3365 4685);
DISPLAY 0.489362 (3365 4685);
FORCEPROP 2 LASTPROP $XRERR UNIQUE?
J 0
(3855 4675);
DISPLAY 0.638298 (3855 4675);
PAINT MONO (3855 4675);
DISPLAY INVISIBLE (3855 4675);
WIRE 16 -1 (4850 2275)(4850 2300);
WIRE 16 -1 (3250 2275)(4850 2275);
FORCEPROP 2 LAST SIG_NAME SW_PVDDIO_P0_BOOTR2
J 0
(3440 2285);
DISPLAY 0.489362 (3440 2285);
FORCEPROP 2 LASTPROP $XRERR UNIQUE?
J 0
(3200 2285);
DISPLAY 0.638298 (3200 2285);
PAINT MONO (3200 2285);
DISPLAY INVISIBLE (3200 2285);
WIRE 16 -1 (4325 2075)(4325 2175);
WIRE 16 -1 (4325 2175)(5825 2175);
WIRE 16 -1 (3250 2175)(4325 2175);
FORCEPROP 2 LAST SIG_NAME SW_PVDDIO_P0_SW2
J 0
(3440 2200);
DISPLAY 0.489362 (3440 2200);
FORCEPROP 2 LASTPROP $XRERR UNIQUE?
J 0
(3200 2200);
DISPLAY 0.638298 (3200 2200);
PAINT MONO (3200 2200);
DISPLAY INVISIBLE (3200 2200);
WIRE 16 -1 (4325 1875)(4325 1575);
FORCEPROP 2 LAST SIG_NAME SW_PVDDIO_P0_SW2_RC
J 0
(4365 1685);
DISPLAY 0.489362 (4365 1685);
FORCEPROP 2 LASTPROP $XRERR UNIQUE?
J 0
(4125 1685);
DISPLAY 0.638298 (4125 1685);
PAINT MONO (4125 1685);
DISPLAY INVISIBLE (4125 1685);
WIRE 16 -1 (5225 1925)(5825 1925);
FORCEPROP 2 LAST SIG_NAME IND_PVDDIO_P0_CPL3
J 0
(5290 1935);
DISPLAY 0.489362 (5290 1935);
WIRE 16 -1 (6625 1925)(7025 1925);
FORCEPROP 2 LAST SIG_NAME IND_PVDDIO_P0_CPL2
J 0
(6640 1935);
DISPLAY 0.489362 (6640 1935);
WIRE 16 -1 (4325 4675)(4325 4325);
FORCEPROP 2 LAST SIG_NAME SW_PVDDIO_P0_SW1_RC
J 0
(4365 4460);
DISPLAY 0.489362 (4365 4460);
FORCEPROP 2 LASTPROP $XRERR UNIQUE?
J 0
(4125 4460);
DISPLAY 0.638298 (4125 4460);
PAINT MONO (4125 4460);
DISPLAY INVISIBLE (4125 4460);
WIRE 16 -1 (5075 4725)(5650 4725);
FORCEPROP 2 LAST SIG_NAME IND_PVDDIO_P0_CPL2
J 0
(5140 4735);
DISPLAY 0.489362 (5140 4735);
WIRE 17 273 (6825 3600)(8325 3600);
WIRE 17 273 (6825 2725)(6825 3600);
WIRE 17 273 (8325 3600)(8325 2725);
WIRE 17 273 (6825 2725)(8325 2725);
DOT 1 (5425 5625);
DOT 1 (5425 6125);
DOT 1 (5450 6125);
DOT 1 (5725 6125);
DOT 1 (5075 5625);
DOT 1 (5075 6125);
DOT 1 (4750 5625);
DOT 1 (4750 6125);
DOT 1 (3425 5625);
DOT 1 (1175 2750);
DOT 1 (1175 3350);
DOT 1 (1525 3350);
DOT 1 (3500 1575);
DOT 1 (3500 1625);
DOT 1 (3500 1675);
DOT 1 (2250 2525);
DOT 1 (3425 2825);
DOT 1 (3675 3350);
DOT 1 (1275 5425);
DOT 1 (1275 6025);
DOT 1 (1625 6025);
DOT 1 (2250 4875);
DOT 1 (2250 5325);
DOT 1 (3500 4375);
DOT 1 (3500 4475);
DOT 1 (3500 4425);
DOT 1 (4025 5625);
DOT 1 (3600 6125);
DOT 1 (4025 6125);
DOT 1 (4325 2175);
DOT 1 (4175 2850);
DOT 1 (4575 2850);
DOT 1 (4975 2850);
DOT 1 (4175 3350);
DOT 1 (4575 3350);
DOT 1 (4975 3350);
DOT 1 (5450 2850);
DOT 1 (5450 3350);
DOT 1 (8075 1750);
DOT 1 (7300 2175);
DOT 1 (7650 2175);
DOT 1 (8075 2175);
DOT 1 (7550 2975);
DOT 1 (7950 2975);
DOT 1 (7550 3400);
DOT 1 (7950 3400);
DOT 1 (4425 5625);
DOT 1 (5450 5625);
DOT 1 (4425 6125);
DOT 1 (7100 4975);
DOT 1 (7200 4975);
DOT 1 (7700 4550);
DOT 1 (7700 4975);
DOT 1 (8125 4550);
DOT 1 (8125 4975);
DOT 1 (6600 6125);
DOT 1 (8425 4550);
DOT 1 (8425 4975);
DOT 1 (4325 4975);
DOT 1 (2250 2075);
FORCENOTE
PU17,PU18,PU19,PU20 = AL021590000/TDA21590
(-375 925) 0;
DISPLAY LEFT (-375 925);
DISPLAY 1.021277 (-375 925);
PAINT WHITE (-375 925);
FORCENOTE
PR101,PR102,PR110,PR109 = CS00002JB13
(-375 850) 0;
DISPLAY LEFT (-375 850);
DISPLAY 1.021277 (-375 850);
PAINT WHITE (-375 850);
FORCENOTE
PR103,PR104,PR111,PR112 = EMPTY
(-375 700) 0;
DISPLAY LEFT (-375 700);
DISPLAY 1.021277 (-375 700);
PAINT WHITE (-375 700);
FORCENOTE
PU17,PU18,PU19,PU20=AL087000A03/MP87000GMJTH-C11D-Z
(-375 375) 0;
DISPLAY LEFT (-375 375);
DISPLAY 1.021277 (-375 375);
PAINT WHITE (-375 375);
FORCENOTE
PC145_7,PC146_8,PC175_9,PC176_10=EMPTY
(-375 300) 0;
DISPLAY LEFT (-375 300);
DISPLAY 1.021277 (-375 300);
PAINT WHITE (-375 300);
FORCENOTE
PC145_7,PC146_8,PC175_9,PC176_10 = EMPTY
(-375 625) 0;
DISPLAY LEFT (-375 625);
DISPLAY 1.021277 (-375 625);
PAINT WHITE (-375 625);
FORCENOTE
PR101,PR102,PR109,PR110=CS00002JB13
(-375 150) 0;
DISPLAY LEFT (-375 150);
DISPLAY 1.021277 (-375 150);
PAINT WHITE (-375 150);
FORCENOTE
PU17,PU18,PU19,PU20 =AL099390004/ISL99390FRZ-TR5935
(-375 1150) 0;
DISPLAY LEFT (-375 1150);
DISPLAY 1.021277 (-375 1150);
PAINT WHITE (-375 1150);
FORCENOTE
PVDDIO_P0_PHASE1
(2550 6075) 0;
DISPLAY LEFT (2550 6075);
DISPLAY 1.021277 (2550 6075);
PAINT WHITE (2550 6075);
FORCENOTE
MAIN SOURCE:RENESAS BOM
(-375 1250) 0;
DISPLAY LEFT (-375 1250);
DISPLAY 1.276596 (-375 1250);
PAINT WHITE (-375 1250);
FORCENOTE
2ND SOURCE:INFENEON BOM
(-375 1025) 0;
DISPLAY LEFT (-375 1025);
DISPLAY 1.276596 (-375 1025);
PAINT WHITE (-375 1025);
FORCENOTE
PR98,PR97,PR106,PR105 = CS00002JB13
(-375 775) 0;
DISPLAY LEFT (-375 775);
DISPLAY 1.021277 (-375 775);
PAINT WHITE (-375 775);
FORCENOTE
PR103,PR104,PR111,PR112=EMPTY
(-375 225) 0;
DISPLAY LEFT (-375 225);
DISPLAY 1.021277 (-375 225);
PAINT WHITE (-375 225);
FORCENOTE
3RD SOURCE:MPS BOM
(-375 475) 0;
DISPLAY LEFT (-375 475);
DISPLAY 1.276596 (-375 475);
PAINT WHITE (-375 475);
FORCENOTE
2ND=CV+15^0TZ01
(6625 2250) 0;
DISPLAY LEFT (6625 2250);
DISPLAY 0.638298 (6625 2250);
PAINT WHITE (6625 2250);
FORCENOTE
DCR=2-3,0.27M OHM
(6625 2300) 0;
DISPLAY LEFT (6625 2300);
DISPLAY 0.638298 (6625 2300);
PAINT WHITE (6625 2300);
FORCENOTE
DCR=1-4,0.105M OHM
(6625 2350) 0;
DISPLAY LEFT (6625 2350);
DISPLAY 0.638298 (6625 2350);
PAINT WHITE (6625 2350);
FORCENOTE
11.0*7.5*12.5
(6625 2400) 0;
DISPLAY LEFT (6625 2400);
DISPLAY 0.638298 (6625 2400);
PAINT WHITE (6625 2400);
FORCENOTE
ISAT:70A@100C
(6625 2450) 0;
DISPLAY LEFT (6625 2450);
DISPLAY 0.638298 (6625 2450);
PAINT WHITE (6625 2450);
FORCENOTE
PGL6303.151HLT
(6625 2500) 0;
DISPLAY LEFT (6625 2500);
DISPLAY 0.638298 (6625 2500);
PAINT WHITE (6625 2500);
FORCENOTE
2ND=CH747LM8822
(7375 2775) 0;
DISPLAY LEFT (7375 2775);
DISPLAY 0.638298 (7375 2775);
PAINT WHITE (7375 2775);
FORCENOTE
7.3*4.3*1.9
(7375 2825) 0;
DISPLAY LEFT (7375 2825);
DISPLAY 0.638298 (7375 2825);
PAINT WHITE (7375 2825);
FORCENOTE
ESR=4.5M OHM
(7375 2875) 0;
DISPLAY LEFT (7375 2875);
DISPLAY 0.638298 (7375 2875);
PAINT WHITE (7375 2875);
FORCENOTE
6.3*8
(5575 5475) 0;
DISPLAY LEFT (5575 5475);
DISPLAY 0.638298 (5575 5475);
PAINT WHITE (5575 5475);
FORCENOTE
2ND=CC72703MD39
(5575 5425) 0;
DISPLAY LEFT (5575 5425);
DISPLAY 0.638298 (5575 5425);
PAINT WHITE (5575 5425);
FORCENOTE
IRIPPLE:5.08A
(5575 5525) 0;
DISPLAY LEFT (5575 5525);
DISPLAY 0.638298 (5575 5525);
PAINT WHITE (5575 5525);
FORCENOTE
ESR=10M OHM
(5575 5575) 0;
DISPLAY LEFT (5575 5575);
DISPLAY 0.638298 (5575 5575);
PAINT WHITE (5575 5575);
FORCENOTE
ISAT:70A@100C
(5950 6000) 0;
DISPLAY LEFT (5950 6000);
DISPLAY 0.638298 (5950 6000);
PAINT WHITE (5950 6000);
FORCENOTE
2ND=CVA50^0MZ07
(5950 5850) 0;
DISPLAY LEFT (5950 5850);
DISPLAY 0.638298 (5950 5850);
PAINT WHITE (5950 5850);
FORCENOTE
3RD=CVA50^0MZ08
(5950 5800) 0;
DISPLAY LEFT (5950 5800);
DISPLAY 0.638298 (5950 5800);
PAINT WHITE (5950 5800);
FORCENOTE
11.0*7.5*12.5
(6475 5200) 0;
DISPLAY LEFT (6475 5200);
DISPLAY 0.638298 (6475 5200);
PAINT WHITE (6475 5200);
FORCENOTE
ISAT:70A@100C
(6475 5250) 0;
DISPLAY LEFT (6475 5250);
DISPLAY 0.638298 (6475 5250);
PAINT WHITE (6475 5250);
FORCENOTE
PGL6303.151HLT
(6475 5300) 0;
DISPLAY LEFT (6475 5300);
DISPLAY 0.638298 (6475 5300);
PAINT WHITE (6475 5300);
FORCENOTE
DCR=1-4,0.105M OHM
(6475 5150) 0;
DISPLAY LEFT (6475 5150);
DISPLAY 0.638298 (6475 5150);
PAINT WHITE (6475 5150);
FORCENOTE
DCR=2-3,0.27M OHM
(6475 5100) 0;
DISPLAY LEFT (6475 5100);
DISPLAY 0.638298 (6475 5100);
PAINT WHITE (6475 5100);
FORCENOTE
2ND=CV+15^0TZ01
(6475 5050) 0;
DISPLAY LEFT (6475 5050);
DISPLAY 0.638298 (6475 5050);
PAINT WHITE (6475 5050);
FORCENOTE
PVDDIO_P0_PHASE2
(2550 3250) 0;
DISPLAY LEFT (2550 3250);
DISPLAY 1.021277 (2550 3250);
PAINT WHITE (2550 3250);
FORCENOTE
BOM NOTE
(-375 1400) 0;
DISPLAY LEFT (-375 1400);
DISPLAY 1.595745 (-375 1400);
PAINT WHITE (-375 1400);
FORCENOTE
PG2292.500HLT
(5950 6050) 0;
DISPLAY LEFT (5950 6050);
DISPLAY 0.638298 (5950 6050);
PAINT WHITE (5950 6050);
FORCENOTE
DCR=0.09M OHM
(5950 5900) 0;
DISPLAY LEFT (5950 5900);
DISPLAY 0.638298 (5950 5900);
PAINT WHITE (5950 5900);
FORCENOTE
6.0*6.1*7.0
(5950 5950) 0;
DISPLAY LEFT (5950 5950);
DISPLAY 0.638298 (5950 5950);
PAINT WHITE (5950 5950);
QUIT
